G04 ================== begin FILE IDENTIFICATION RECORD ==================*
G04 Layout Name:  14545-sa.brd*
G04 Film Name:    TMASK*
G04 File Format:  Gerber RS274X*
G04 File Origin:  Cadence Allegro 16.5-S056*
G04 Origin Date:  Fri Aug 01 17:58:21 2014*
G04 *
G04 Layer:  VIA CLASS/SOLDERMASK_TOP*
G04 Layer:  PIN/SOLDERMASK_TOP*
G04 Layer:  PACKAGE GEOMETRY/SOLDERMASK_TOP*
G04 Layer:  DRAWING FORMAT/LAYER_PCB_STORY*
G04 Layer:  DRAWING FORMAT/LAYER_SOLDER_T*
G04 Layer:  BOARD GEOMETRY/SOLDERMASK_TOP*
G04 *
G04 Offset:    (0.00 0.00)*
G04 Mirror:    No*
G04 Mode:      Positive*
G04 Rotation:  0*
G04 FullContactRelief:  No*
G04 UndefLineWidth:     6.00*
G04 ================== end FILE IDENTIFICATION RECORD ====================*
%FSLAX35Y35*MOIN*%
%IR0*IPPOS*OFA0.00000B0.00000*MIA0B0*SFA1.00000B1.00000*%
%AMMACRO48*
4,1,40,.017,-.013,
.017,.013,
.016939,.013695,
.016759,.014368,
.016464,.015,
.016064,.015571,
.015571,.016064,
.015,.016464,
.014368,.016759,
.013695,.016939,
.013,.017,
-.013,.017,
-.013695,.016939,
-.014368,.016759,
-.015,.016464,
-.015571,.016064,
-.016064,.015571,
-.016464,.015,
-.016759,.014368,
-.016939,.013695,
-.017,.013,
-.017,-.013,
-.016939,-.013695,
-.016759,-.014368,
-.016464,-.015,
-.016064,-.015571,
-.015571,-.016064,
-.015,-.016464,
-.014368,-.016759,
-.013695,-.016939,
-.013,-.017,
.013,-.017,
.013695,-.016939,
.014368,-.016759,
.015,-.016464,
.015571,-.016064,
.016064,-.015571,
.016464,-.015,
.016759,-.014368,
.016939,-.013695,
.017,-.013,
0.0*
%
%ADD48MACRO48*%
%AMMACRO20*
4,1,40,.013,.017,
-.013,.017,
-.013695,.016939,
-.014368,.016759,
-.015,.016464,
-.015571,.016064,
-.016064,.015571,
-.016464,.015,
-.016759,.014368,
-.016939,.013695,
-.017,.013,
-.017,-.013,
-.016939,-.013695,
-.016759,-.014368,
-.016464,-.015,
-.016064,-.015571,
-.015571,-.016064,
-.015,-.016464,
-.014368,-.016759,
-.013695,-.016939,
-.013,-.017,
.013,-.017,
.013695,-.016939,
.014368,-.016759,
.015,-.016464,
.015571,-.016064,
.016064,-.015571,
.016464,-.015,
.016759,-.014368,
.016939,-.013695,
.017,-.013,
.017,.013,
.016939,.013695,
.016759,.014368,
.016464,.015,
.016064,.015571,
.015571,.016064,
.015,.016464,
.014368,.016759,
.013695,.016939,
.013,.017,
0.0*
%
%ADD20MACRO20*%
%ADD16O,.103X.06*%
%ADD83R,.23X.032*%
%ADD63R,.045X.11*%
%ADD21R,.11X.045*%
%ADD13R,.142X.028*%
%ADD55C,.022*%
%ADD30C,.032*%
%ADD29C,.028*%
%ADD17C,.073*%
%ADD12C,.091*%
%ADD11C,.086*%
%AMMACRO68*
4,1,40,-.007,-.0225,
-.008389,-.022378,
-.009736,-.022018,
-.011,-.021428,
-.012142,-.020628,
-.013128,-.019642,
-.013928,-.0185,
-.014518,-.017236,
-.014878,-.015889,
-.015,-.0145,
-.015,.0145,
-.014878,.015889,
-.014518,.017236,
-.013928,.0185,
-.013128,.019642,
-.012142,.020628,
-.011,.021428,
-.009736,.022018,
-.008389,.022378,
-.007,.0225,
.007,.0225,
.008389,.022378,
.009736,.022018,
.011,.021428,
.012142,.020628,
.013128,.019642,
.013928,.0185,
.014518,.017236,
.014878,.015889,
.015,.0145,
.015,-.0145,
.014878,-.015889,
.014518,-.017236,
.013928,-.0185,
.013128,-.019642,
.012142,-.020628,
.011,-.021428,
.009736,-.022018,
.008389,-.022378,
.007,-.0225,
-.007,-.0225,
0.0*
%
%ADD68MACRO68*%
%AMMACRO31*
4,1,40,.011,-.007,
.011,.007,
.010939,.007695,
.010759,.008368,
.010464,.009,
.010064,.009571,
.009571,.010064,
.009,.010464,
.008368,.010759,
.007695,.010939,
.007,.011,
-.007,.011,
-.007695,.010939,
-.008368,.010759,
-.009,.010464,
-.009571,.010064,
-.010064,.009571,
-.010464,.009,
-.010759,.008368,
-.010939,.007695,
-.011,.007,
-.011,-.007,
-.010939,-.007695,
-.010759,-.008368,
-.010464,-.009,
-.010064,-.009571,
-.009571,-.010064,
-.009,-.010464,
-.008368,-.010759,
-.007695,-.010939,
-.007,-.011,
.007,-.011,
.007695,-.010939,
.008368,-.010759,
.009,-.010464,
.009571,-.010064,
.010064,-.009571,
.010464,-.009,
.010759,-.008368,
.010939,-.007695,
.011,-.007,
0.0*
%
%ADD31MACRO31*%
%AMMACRO24*
4,1,40,.007,.011,
-.007,.011,
-.007695,.010939,
-.008368,.010759,
-.009,.010464,
-.009571,.010064,
-.010064,.009571,
-.010464,.009,
-.010759,.008368,
-.010939,.007695,
-.011,.007,
-.011,-.007,
-.010939,-.007695,
-.010759,-.008368,
-.010464,-.009,
-.010064,-.009571,
-.009571,-.010064,
-.009,-.010464,
-.008368,-.010759,
-.007695,-.010939,
-.007,-.011,
.007,-.011,
.007695,-.010939,
.008368,-.010759,
.009,-.010464,
.009571,-.010064,
.010064,-.009571,
.010464,-.009,
.010759,-.008368,
.010939,-.007695,
.011,-.007,
.011,.007,
.010939,.007695,
.010759,.008368,
.010464,.009,
.010064,.009571,
.009571,.010064,
.009,.010464,
.008368,.010759,
.007695,.010939,
.007,.011,
0.0*
%
%ADD24MACRO24*%
%AMMACRO46*
4,1,40,-.012,.008,
-.012,-.008,
-.011939,-.008695,
-.011759,-.009368,
-.011464,-.01,
-.011064,-.010571,
-.010571,-.011064,
-.01,-.011464,
-.009368,-.011759,
-.008695,-.011939,
-.008,-.012,
.008,-.012,
.008695,-.011939,
.009368,-.011759,
.01,-.011464,
.010571,-.011064,
.011064,-.010571,
.011464,-.01,
.011759,-.009368,
.011939,-.008695,
.012,-.008,
.012,.008,
.011939,.008695,
.011759,.009368,
.011464,.01,
.011064,.010571,
.010571,.011064,
.01,.011464,
.009368,.011759,
.008695,.011939,
.008,.012,
-.008,.012,
-.008695,.011939,
-.009368,.011759,
-.01,.011464,
-.010571,.011064,
-.011064,.010571,
-.011464,.01,
-.011759,.009368,
-.011939,.008695,
-.012,.008,
0.0*
%
%ADD46MACRO46*%
%AMMACRO61*
4,1,40,.008,.012,
-.008,.012,
-.008695,.011939,
-.009368,.011759,
-.01,.011464,
-.010571,.011064,
-.011064,.010571,
-.011464,.01,
-.011759,.009368,
-.011939,.008695,
-.012,.008,
-.012,-.008,
-.011939,-.008695,
-.011759,-.009368,
-.011464,-.01,
-.011064,-.010571,
-.010571,-.011064,
-.01,-.011464,
-.009368,-.011759,
-.008695,-.011939,
-.008,-.012,
.008,-.012,
.008695,-.011939,
.009368,-.011759,
.01,-.011464,
.010571,-.011064,
.011064,-.010571,
.011464,-.01,
.011759,-.009368,
.011939,-.008695,
.012,-.008,
.012,.008,
.011939,.008695,
.011759,.009368,
.011464,.01,
.011064,.010571,
.010571,.011064,
.01,.011464,
.009368,.011759,
.008695,.011939,
.008,.012,
0.0*
%
%ADD61MACRO61*%
%AMMACRO74*
4,1,6,.0135,-.025,
-.0065,-.005,
-.0135,-.005,
-.0135,.005,
-.0065,.005,
.0135,.025,
.0135,-.025,
0.0*
%
%ADD74MACRO74*%
%AMMACRO39*
4,1,40,-.013,-.017,
.013,-.017,
.013695,-.016939,
.014368,-.016759,
.015,-.016464,
.015571,-.016064,
.016064,-.015571,
.016464,-.015,
.016759,-.014368,
.016939,-.013695,
.017,-.013,
.017,.013,
.016939,.013695,
.016759,.014368,
.016464,.015,
.016064,.015571,
.015571,.016064,
.015,.016464,
.014368,.016759,
.013695,.016939,
.013,.017,
-.013,.017,
-.013695,.016939,
-.014368,.016759,
-.015,.016464,
-.015571,.016064,
-.016064,.015571,
-.016464,.015,
-.016759,.014368,
-.016939,.013695,
-.017,.013,
-.017,-.013,
-.016939,-.013695,
-.016759,-.014368,
-.016464,-.015,
-.016064,-.015571,
-.015571,-.016064,
-.015,-.016464,
-.014368,-.016759,
-.013695,-.016939,
-.013,-.017,
0.0*
%
%ADD39MACRO39*%
%AMMACRO49*
4,1,40,-.017,.013,
-.017,-.013,
-.016939,-.013695,
-.016759,-.014368,
-.016464,-.015,
-.016064,-.015571,
-.015571,-.016064,
-.015,-.016464,
-.014368,-.016759,
-.013695,-.016939,
-.013,-.017,
.013,-.017,
.013695,-.016939,
.014368,-.016759,
.015,-.016464,
.015571,-.016064,
.016064,-.015571,
.016464,-.015,
.016759,-.014368,
.016939,-.013695,
.017,-.013,
.017,.013,
.016939,.013695,
.016759,.014368,
.016464,.015,
.016064,.015571,
.015571,.016064,
.015,.016464,
.014368,.016759,
.013695,.016939,
.013,.017,
-.013,.017,
-.013695,.016939,
-.014368,.016759,
-.015,.016464,
-.015571,.016064,
-.016064,.015571,
-.016464,.015,
-.016759,.014368,
-.016939,.013695,
-.017,.013,
0.0*
%
%ADD49MACRO49*%
%AMMACRO56*
4,1,6,.005,.0135,
.005,.0065,
.025,-.0135,
-.025,-.0135,
-.005,.0065,
-.005,.0135,
.005,.0135,
0.0*
%
%ADD56MACRO56*%
%AMMACRO32*
4,1,40,.011,-.007,
.011,.007,
.010939,.007695,
.010759,.008368,
.010464,.009,
.010064,.009571,
.009571,.010064,
.009,.010464,
.008368,.010759,
.007695,.010939,
.007,.011,
-.007,.011,
-.007695,.010939,
-.008368,.010759,
-.009,.010464,
-.009571,.010064,
-.010064,.009571,
-.010464,.009,
-.010759,.008368,
-.010939,.007695,
-.011,.007,
-.011,-.007,
-.010939,-.007695,
-.010759,-.008368,
-.010464,-.009,
-.010064,-.009571,
-.009571,-.010064,
-.009,-.010464,
-.008368,-.010759,
-.007695,-.010939,
-.007,-.011,
.007,-.011,
.007695,-.010939,
.008368,-.010759,
.009,-.010464,
.009571,-.010064,
.010064,-.009571,
.010464,-.009,
.010759,-.008368,
.010939,-.007695,
.011,-.007,
0.0*
%
%ADD32MACRO32*%
%AMMACRO25*
4,1,40,.007,.011,
-.007,.011,
-.007695,.010939,
-.008368,.010759,
-.009,.010464,
-.009571,.010064,
-.010064,.009571,
-.010464,.009,
-.010759,.008368,
-.010939,.007695,
-.011,.007,
-.011,-.007,
-.010939,-.007695,
-.010759,-.008368,
-.010464,-.009,
-.010064,-.009571,
-.009571,-.010064,
-.009,-.010464,
-.008368,-.010759,
-.007695,-.010939,
-.007,-.011,
.007,-.011,
.007695,-.010939,
.008368,-.010759,
.009,-.010464,
.009571,-.010064,
.010064,-.009571,
.010464,-.009,
.010759,-.008368,
.010939,-.007695,
.011,-.007,
.011,.007,
.010939,.007695,
.010759,.008368,
.010464,.009,
.010064,.009571,
.009571,.010064,
.009,.010464,
.008368,.010759,
.007695,.010939,
.007,.011,
0.0*
%
%ADD25MACRO25*%
%AMMACRO71*
4,1,20,.0635,-.1075,
.049,-.1075,
.049,-.118,
.0395,-.118,
.0395,-.1075,
-.0395,-.1075,
-.0395,-.118,
-.049,-.118,
-.049,-.1075,
-.0635,-.1075,
-.0635,.1075,
-.049,.1075,
-.049,.118,
-.0395,.118,
-.0395,.1075,
.0395,.1075,
.0395,.118,
.049,.118,
.049,.1075,
.0635,.1075,
.0635,-.1075,
0.0*
%
%ADD71MACRO71*%
%AMMACRO45*
4,1,40,-.012,.008,
-.012,-.008,
-.011939,-.008695,
-.011759,-.009368,
-.011464,-.01,
-.011064,-.010571,
-.010571,-.011064,
-.01,-.011464,
-.009368,-.011759,
-.008695,-.011939,
-.008,-.012,
.008,-.012,
.008695,-.011939,
.009368,-.011759,
.01,-.011464,
.010571,-.011064,
.011064,-.010571,
.011464,-.01,
.011759,-.009368,
.011939,-.008695,
.012,-.008,
.012,.008,
.011939,.008695,
.011759,.009368,
.011464,.01,
.011064,.010571,
.010571,.011064,
.01,.011464,
.009368,.011759,
.008695,.011939,
.008,.012,
-.008,.012,
-.008695,.011939,
-.009368,.011759,
-.01,.011464,
-.010571,.011064,
-.011064,.010571,
-.011464,.01,
-.011759,.009368,
-.011939,.008695,
-.012,.008,
0.0*
%
%ADD45MACRO45*%
%AMMACRO60*
4,1,40,.008,.012,
-.008,.012,
-.008695,.011939,
-.009368,.011759,
-.01,.011464,
-.010571,.011064,
-.011064,.010571,
-.011464,.01,
-.011759,.009368,
-.011939,.008695,
-.012,.008,
-.012,-.008,
-.011939,-.008695,
-.011759,-.009368,
-.011464,-.01,
-.011064,-.010571,
-.010571,-.011064,
-.01,-.011464,
-.009368,-.011759,
-.008695,-.011939,
-.008,-.012,
.008,-.012,
.008695,-.011939,
.009368,-.011759,
.01,-.011464,
.010571,-.011064,
.011064,-.010571,
.011464,-.01,
.011759,-.009368,
.011939,-.008695,
.012,-.008,
.012,.008,
.011939,.008695,
.011759,.009368,
.011464,.01,
.011064,.010571,
.010571,.011064,
.01,.011464,
.009368,.011759,
.008695,.011939,
.008,.012,
0.0*
%
%ADD60MACRO60*%
%AMMACRO40*
4,1,40,-.013,-.017,
.013,-.017,
.013695,-.016939,
.014368,-.016759,
.015,-.016464,
.015571,-.016064,
.016064,-.015571,
.016464,-.015,
.016759,-.014368,
.016939,-.013695,
.017,-.013,
.017,.013,
.016939,.013695,
.016759,.014368,
.016464,.015,
.016064,.015571,
.015571,.016064,
.015,.016464,
.014368,.016759,
.013695,.016939,
.013,.017,
-.013,.017,
-.013695,.016939,
-.014368,.016759,
-.015,.016464,
-.015571,.016064,
-.016064,.015571,
-.016464,.015,
-.016759,.014368,
-.016939,.013695,
-.017,.013,
-.017,-.013,
-.016939,-.013695,
-.016759,-.014368,
-.016464,-.015,
-.016064,-.015571,
-.015571,-.016064,
-.015,-.016464,
-.014368,-.016759,
-.013695,-.016939,
-.013,-.017,
0.0*
%
%ADD40MACRO40*%
%AMMACRO50*
4,1,40,-.017,.013,
-.017,-.013,
-.016939,-.013695,
-.016759,-.014368,
-.016464,-.015,
-.016064,-.015571,
-.015571,-.016064,
-.015,-.016464,
-.014368,-.016759,
-.013695,-.016939,
-.013,-.017,
.013,-.017,
.013695,-.016939,
.014368,-.016759,
.015,-.016464,
.015571,-.016064,
.016064,-.015571,
.016464,-.015,
.016759,-.014368,
.016939,-.013695,
.017,-.013,
.017,.013,
.016939,.013695,
.016759,.014368,
.016464,.015,
.016064,.015571,
.015571,.016064,
.015,.016464,
.014368,.016759,
.013695,.016939,
.013,.017,
-.013,.017,
-.013695,.016939,
-.014368,.016759,
-.015,.016464,
-.015571,.016064,
-.016064,.015571,
-.016464,.015,
-.016759,.014368,
-.016939,.013695,
-.017,.013,
0.0*
%
%ADD50MACRO50*%
%ADD36R,.04X.022*%
%ADD78R,.06X.012*%
%ADD77R,.022X.04*%
%ADD81R,.023X.04*%
%ADD79R,.06X.014*%
%ADD72R,.044X.012*%
%ADD62R,.04X.016*%
%ADD67R,.014X.06*%
%ADD65R,.016X.04*%
%ADD53R,.012X.044*%
%ADD28R,.045X.03*%
%ADD54R,.133X.128*%
%ADD58R,.128X.133*%
%ADD22R,.075X.02*%
%ADD80R,.05X.065*%
%ADD23R,.036X.024*%
%ADD42R,.065X.05*%
%ADD41R,.065X.025*%
%ADD15C,.315*%
%ADD69R,.025X.065*%
%ADD66R,.048X.016*%
%ADD14R,.045X.055*%
%ADD84C,.146*%
%ADD64R,.016X.048*%
%ADD51R,.055X.045*%
%ADD70R,.054X.074*%
%ADD18R,.094X.026*%
%ADD35R,.09X.095*%
%ADD10R,.16X.16*%
%AMMACRO76*
4,1,40,-.0225,.007,
-.022378,.008389,
-.022018,.009736,
-.021428,.011,
-.020628,.012142,
-.019642,.013128,
-.0185,.013928,
-.017236,.014518,
-.015889,.014878,
-.0145,.015,
.0145,.015,
.015889,.014878,
.017236,.014518,
.0185,.013928,
.019642,.013128,
.020628,.012142,
.021428,.011,
.022018,.009736,
.022378,.008389,
.0225,.007,
.0225,-.007,
.022378,-.008389,
.022018,-.009736,
.021428,-.011,
.020628,-.012142,
.019642,-.013128,
.0185,-.013928,
.017236,-.014518,
.015889,-.014878,
.0145,-.015,
-.0145,-.015,
-.015889,-.014878,
-.017236,-.014518,
-.0185,-.013928,
-.019642,-.013128,
-.020628,-.012142,
-.021428,-.011,
-.022018,-.009736,
-.022378,-.008389,
-.0225,-.007,
-.0225,.007,
0.0*
%
%ADD76MACRO76*%
%AMMACRO75*
4,1,40,.007,.0225,
.008389,.022378,
.009736,.022018,
.011,.021428,
.012142,.020628,
.013128,.019642,
.013928,.0185,
.014518,.017236,
.014878,.015889,
.015,.0145,
.015,-.0145,
.014878,-.015889,
.014518,-.017236,
.013928,-.0185,
.013128,-.019642,
.012142,-.020628,
.011,-.021428,
.009736,-.022018,
.008389,-.022378,
.007,-.0225,
-.007,-.0225,
-.008389,-.022378,
-.009736,-.022018,
-.011,-.021428,
-.012142,-.020628,
-.013128,-.019642,
-.013928,-.0185,
-.014518,-.017236,
-.014878,-.015889,
-.015,-.0145,
-.015,.0145,
-.014878,.015889,
-.014518,.017236,
-.013928,.0185,
-.013128,.019642,
-.012142,.020628,
-.011,.021428,
-.009736,.022018,
-.008389,.022378,
-.007,.0225,
.007,.0225,
0.0*
%
%ADD75MACRO75*%
%ADD59R,.095X.09*%
%ADD82R,.089X.059*%
%AMMACRO44*
4,1,40,-.008,-.012,
.008,-.012,
.008695,-.011939,
.009368,-.011759,
.01,-.011464,
.010571,-.011064,
.011064,-.010571,
.011464,-.01,
.011759,-.009368,
.011939,-.008695,
.012,-.008,
.012,.008,
.011939,.008695,
.011759,.009368,
.011464,.01,
.011064,.010571,
.010571,.011064,
.01,.011464,
.009368,.011759,
.008695,.011939,
.008,.012,
-.008,.012,
-.008695,.011939,
-.009368,.011759,
-.01,.011464,
-.010571,.011064,
-.011064,.010571,
-.011464,.01,
-.011759,.009368,
-.011939,.008695,
-.012,.008,
-.012,-.008,
-.011939,-.008695,
-.011759,-.009368,
-.011464,-.01,
-.011064,-.010571,
-.010571,-.011064,
-.01,-.011464,
-.009368,-.011759,
-.008695,-.011939,
-.008,-.012,
0.0*
%
%ADD44MACRO44*%
%AMMACRO38*
4,1,40,.012,-.008,
.012,.008,
.011939,.008695,
.011759,.009368,
.011464,.01,
.011064,.010571,
.010571,.011064,
.01,.011464,
.009368,.011759,
.008695,.011939,
.008,.012,
-.008,.012,
-.008695,.011939,
-.009368,.011759,
-.01,.011464,
-.010571,.011064,
-.011064,.010571,
-.011464,.01,
-.011759,.009368,
-.011939,.008695,
-.012,.008,
-.012,-.008,
-.011939,-.008695,
-.011759,-.009368,
-.011464,-.01,
-.011064,-.010571,
-.010571,-.011064,
-.01,-.011464,
-.009368,-.011759,
-.008695,-.011939,
-.008,-.012,
.008,-.012,
.008695,-.011939,
.009368,-.011759,
.01,-.011464,
.010571,-.011064,
.011064,-.010571,
.011464,-.01,
.011759,-.009368,
.011939,-.008695,
.012,-.008,
0.0*
%
%ADD38MACRO38*%
%AMMACRO26*
4,1,40,-.007,-.011,
.007,-.011,
.007695,-.010939,
.008368,-.010759,
.009,-.010464,
.009571,-.010064,
.010064,-.009571,
.010464,-.009,
.010759,-.008368,
.010939,-.007695,
.011,-.007,
.011,.007,
.010939,.007695,
.010759,.008368,
.010464,.009,
.010064,.009571,
.009571,.010064,
.009,.010464,
.008368,.010759,
.007695,.010939,
.007,.011,
-.007,.011,
-.007695,.010939,
-.008368,.010759,
-.009,.010464,
-.009571,.010064,
-.010064,.009571,
-.010464,.009,
-.010759,.008368,
-.010939,.007695,
-.011,.007,
-.011,-.007,
-.010939,-.007695,
-.010759,-.008368,
-.010464,-.009,
-.010064,-.009571,
-.009571,-.010064,
-.009,-.010464,
-.008368,-.010759,
-.007695,-.010939,
-.007,-.011,
0.0*
%
%ADD26MACRO26*%
%AMMACRO33*
4,1,40,-.011,.007,
-.011,-.007,
-.010939,-.007695,
-.010759,-.008368,
-.010464,-.009,
-.010064,-.009571,
-.009571,-.010064,
-.009,-.010464,
-.008368,-.010759,
-.007695,-.010939,
-.007,-.011,
.007,-.011,
.007695,-.010939,
.008368,-.010759,
.009,-.010464,
.009571,-.010064,
.010064,-.009571,
.010464,-.009,
.010759,-.008368,
.010939,-.007695,
.011,-.007,
.011,.007,
.010939,.007695,
.010759,.008368,
.010464,.009,
.010064,.009571,
.009571,.010064,
.009,.010464,
.008368,.010759,
.007695,.010939,
.007,.011,
-.007,.011,
-.007695,.010939,
-.008368,.010759,
-.009,.010464,
-.009571,.010064,
-.010064,.009571,
-.010464,.009,
-.010759,.008368,
-.010939,.007695,
-.011,.007,
0.0*
%
%ADD33MACRO33*%
%AMMACRO57*
4,1,6,.025,.0135,
.005,-.0065,
.005,-.0135,
-.005,-.0135,
-.005,-.0065,
-.025,.0135,
.025,.0135,
0.0*
%
%ADD57MACRO57*%
%AMMACRO47*
4,1,40,.017,-.013,
.017,.013,
.016939,.013695,
.016759,.014368,
.016464,.015,
.016064,.015571,
.015571,.016064,
.015,.016464,
.014368,.016759,
.013695,.016939,
.013,.017,
-.013,.017,
-.013695,.016939,
-.014368,.016759,
-.015,.016464,
-.015571,.016064,
-.016064,.015571,
-.016464,.015,
-.016759,.014368,
-.016939,.013695,
-.017,.013,
-.017,-.013,
-.016939,-.013695,
-.016759,-.014368,
-.016464,-.015,
-.016064,-.015571,
-.015571,-.016064,
-.015,-.016464,
-.014368,-.016759,
-.013695,-.016939,
-.013,-.017,
.013,-.017,
.013695,-.016939,
.014368,-.016759,
.015,-.016464,
.015571,-.016064,
.016064,-.015571,
.016464,-.015,
.016759,-.014368,
.016939,-.013695,
.017,-.013,
0.0*
%
%ADD47MACRO47*%
%AMMACRO19*
4,1,40,.013,.017,
-.013,.017,
-.013695,.016939,
-.014368,.016759,
-.015,.016464,
-.015571,.016064,
-.016064,.015571,
-.016464,.015,
-.016759,.014368,
-.016939,.013695,
-.017,.013,
-.017,-.013,
-.016939,-.013695,
-.016759,-.014368,
-.016464,-.015,
-.016064,-.015571,
-.015571,-.016064,
-.015,-.016464,
-.014368,-.016759,
-.013695,-.016939,
-.013,-.017,
.013,-.017,
.013695,-.016939,
.014368,-.016759,
.015,-.016464,
.015571,-.016064,
.016064,-.015571,
.016464,-.015,
.016759,-.014368,
.016939,-.013695,
.017,-.013,
.017,.013,
.016939,.013695,
.016759,.014368,
.016464,.015,
.016064,.015571,
.015571,.016064,
.015,.016464,
.014368,.016759,
.013695,.016939,
.013,.017,
0.0*
%
%ADD19MACRO19*%
%AMMACRO73*
4,1,6,.0135,-.005,
.0065,-.005,
-.0135,-.025,
-.0135,.025,
.0065,.005,
.0135,.005,
.0135,-.005,
0.0*
%
%ADD73MACRO73*%
%AMMACRO52*
4,1,20,.1075,.0635,
.1075,.049,
.118,.049,
.118,.0395,
.1075,.0395,
.1075,-.0395,
.118,-.0395,
.118,-.049,
.1075,-.049,
.1075,-.0635,
-.1075,-.0635,
-.1075,-.049,
-.118,-.049,
-.118,-.0395,
-.1075,-.0395,
-.1075,.0395,
-.118,.0395,
-.118,.049,
-.1075,.049,
-.1075,.0635,
.1075,.0635,
0.0*
%
%ADD52MACRO52*%
%AMMACRO43*
4,1,40,-.008,-.012,
.008,-.012,
.008695,-.011939,
.009368,-.011759,
.01,-.011464,
.010571,-.011064,
.011064,-.010571,
.011464,-.01,
.011759,-.009368,
.011939,-.008695,
.012,-.008,
.012,.008,
.011939,.008695,
.011759,.009368,
.011464,.01,
.011064,.010571,
.010571,.011064,
.01,.011464,
.009368,.011759,
.008695,.011939,
.008,.012,
-.008,.012,
-.008695,.011939,
-.009368,.011759,
-.01,.011464,
-.010571,.011064,
-.011064,.010571,
-.011464,.01,
-.011759,.009368,
-.011939,.008695,
-.012,.008,
-.012,-.008,
-.011939,-.008695,
-.011759,-.009368,
-.011464,-.01,
-.011064,-.010571,
-.010571,-.011064,
-.01,-.011464,
-.009368,-.011759,
-.008695,-.011939,
-.008,-.012,
0.0*
%
%ADD43MACRO43*%
%AMMACRO37*
4,1,40,.012,-.008,
.012,.008,
.011939,.008695,
.011759,.009368,
.011464,.01,
.011064,.010571,
.010571,.011064,
.01,.011464,
.009368,.011759,
.008695,.011939,
.008,.012,
-.008,.012,
-.008695,.011939,
-.009368,.011759,
-.01,.011464,
-.010571,.011064,
-.011064,.010571,
-.011464,.01,
-.011759,.009368,
-.011939,.008695,
-.012,.008,
-.012,-.008,
-.011939,-.008695,
-.011759,-.009368,
-.011464,-.01,
-.011064,-.010571,
-.010571,-.011064,
-.01,-.011464,
-.009368,-.011759,
-.008695,-.011939,
-.008,-.012,
.008,-.012,
.008695,-.011939,
.009368,-.011759,
.01,-.011464,
.010571,-.011064,
.011064,-.010571,
.011464,-.01,
.011759,-.009368,
.011939,-.008695,
.012,-.008,
0.0*
%
%ADD37MACRO37*%
%AMMACRO27*
4,1,40,-.007,-.011,
.007,-.011,
.007695,-.010939,
.008368,-.010759,
.009,-.010464,
.009571,-.010064,
.010064,-.009571,
.010464,-.009,
.010759,-.008368,
.010939,-.007695,
.011,-.007,
.011,.007,
.010939,.007695,
.010759,.008368,
.010464,.009,
.010064,.009571,
.009571,.010064,
.009,.010464,
.008368,.010759,
.007695,.010939,
.007,.011,
-.007,.011,
-.007695,.010939,
-.008368,.010759,
-.009,.010464,
-.009571,.010064,
-.010064,.009571,
-.010464,.009,
-.010759,.008368,
-.010939,.007695,
-.011,.007,
-.011,-.007,
-.010939,-.007695,
-.010759,-.008368,
-.010464,-.009,
-.010064,-.009571,
-.009571,-.010064,
-.009,-.010464,
-.008368,-.010759,
-.007695,-.010939,
-.007,-.011,
0.0*
%
%ADD27MACRO27*%
%AMMACRO34*
4,1,40,-.011,.007,
-.011,-.007,
-.010939,-.007695,
-.010759,-.008368,
-.010464,-.009,
-.010064,-.009571,
-.009571,-.010064,
-.009,-.010464,
-.008368,-.010759,
-.007695,-.010939,
-.007,-.011,
.007,-.011,
.007695,-.010939,
.008368,-.010759,
.009,-.010464,
.009571,-.010064,
.010064,-.009571,
.010464,-.009,
.010759,-.008368,
.010939,-.007695,
.011,-.007,
.011,.007,
.010939,.007695,
.010759,.008368,
.010464,.009,
.010064,.009571,
.009571,.010064,
.009,.010464,
.008368,.010759,
.007695,.010939,
.007,.011,
-.007,.011,
-.007695,.010939,
-.008368,.010759,
-.009,.010464,
-.009571,.010064,
-.010064,.009571,
-.010464,.009,
-.010759,.008368,
-.010939,.007695,
-.011,.007,
0.0*
%
%ADD34MACRO34*%
%ADD85C,.02*%
%ADD86C,.006*%
G75*
%LPD*%
G75*
G36*
G01X1017308Y1473722D02*
X991708D01*
Y1491397D01*
X1017308D01*
Y1473722D01*
G37*
G36*
G01X991708Y1453247D02*
X1017308D01*
Y1470922D01*
X991708D01*
Y1453247D01*
G37*
G36*
G01X1017308Y1433722D02*
X991708D01*
Y1451397D01*
X1017308D01*
Y1433722D01*
G37*
G36*
G01Y1553722D02*
X991708D01*
Y1571397D01*
X1017308D01*
Y1553722D01*
G37*
G36*
G01Y1513722D02*
X991708D01*
Y1531397D01*
X1017308D01*
Y1513722D01*
G37*
G36*
G01X991708Y1533247D02*
X1017308D01*
Y1550922D01*
X991708D01*
Y1533247D01*
G37*
G36*
G01Y1493247D02*
X1017308D01*
Y1510922D01*
X991708D01*
Y1493247D01*
G37*
G36*
G01X1017307Y1593722D02*
Y1610922D01*
X991708D01*
Y1593722D01*
X1017307D01*
G37*
G36*
G01X991708Y1573247D02*
X1017308D01*
Y1590922D01*
X991708D01*
Y1573247D01*
G37*
G54D10*
X-30766Y56622D03*
X-33866Y1947322D03*
X21499Y17050D03*
X1010999Y18550D03*
X1008999Y1968550D03*
X1073334Y50022D03*
G54D11*
X-39052Y28742D03*
X-43327Y310478D03*
X-39686Y917251D03*
X-38801Y1082342D03*
X-44886Y1294251D03*
X-43103Y1928864D03*
X1071932Y32074D03*
X1074813Y1348051D03*
X1076613Y1740651D03*
X1074813Y1957551D03*
G54D20*
X26300Y119500D03*
Y114500D03*
X185799Y95050D03*
X906299Y115050D03*
X896200Y1716200D03*
X884201Y1693850D03*
X971000Y1665500D03*
Y1660500D03*
G54D12*
X9843Y153168D03*
Y265767D03*
Y353144D03*
Y717711D03*
Y762617D03*
Y875216D03*
Y1137420D03*
Y1250019D03*
Y1337396D03*
Y1701963D03*
Y1746869D03*
Y1859468D03*
G54D30*
X38999Y372160D03*
X57400Y610900D03*
X29999Y849660D03*
X20499Y1315050D03*
X34999Y1572550D03*
X35900Y1832700D03*
X26499Y1935550D03*
X26999Y1941550D03*
X102999Y29050D03*
X100999Y468550D03*
X162500Y557500D03*
X109999Y872550D03*
X126999Y1119050D03*
X141499Y1267050D03*
X107699Y1510950D03*
X118999Y1525550D03*
X96999Y1632050D03*
X197226Y90428D03*
X202999Y90550D03*
X233100Y1929800D03*
X276500Y319500D03*
X288999Y723550D03*
X655049Y1810634D03*
X824499Y205050D03*
X807499Y1089550D03*
X803499Y1496050D03*
X814499Y1809050D03*
X806499Y1903550D03*
X914999Y103050D03*
X920999D03*
X843700Y312200D03*
X841500Y713000D03*
G54D21*
X28000Y83750D03*
Y102250D03*
X27500Y921250D03*
Y902750D03*
X18500Y1067750D03*
Y1086250D03*
X42600Y1886050D03*
Y1867550D03*
X117999Y1143550D03*
Y1162050D03*
G54D22*
X77166Y114212D03*
Y117362D03*
Y120511D03*
Y123661D03*
Y126811D03*
Y129960D03*
Y133110D03*
Y519724D03*
Y522874D03*
Y526023D03*
Y529173D03*
Y532323D03*
Y535472D03*
Y538622D03*
Y925236D03*
Y928386D03*
Y931535D03*
Y934685D03*
Y937835D03*
Y940984D03*
Y944134D03*
Y1330748D03*
Y1333898D03*
Y1337047D03*
Y1340197D03*
Y1343347D03*
Y1346496D03*
Y1349646D03*
Y1736260D03*
Y1739410D03*
Y1742559D03*
Y1745709D03*
Y1748859D03*
Y1752008D03*
Y1755158D03*
X159055Y255866D03*
Y252716D03*
Y249567D03*
Y246417D03*
Y243267D03*
Y240118D03*
Y236968D03*
Y645630D03*
Y642480D03*
Y661378D03*
Y658228D03*
Y655079D03*
Y651929D03*
Y648779D03*
Y1060591D03*
Y1057441D03*
Y1054291D03*
Y1051142D03*
Y1047992D03*
Y1066890D03*
Y1063740D03*
Y1472402D03*
Y1469252D03*
Y1466103D03*
Y1462953D03*
Y1459803D03*
Y1456654D03*
Y1453504D03*
Y1877914D03*
Y1874764D03*
Y1871615D03*
Y1868465D03*
Y1865315D03*
Y1862166D03*
Y1859016D03*
X887401Y255866D03*
Y252716D03*
Y249567D03*
Y246417D03*
Y243267D03*
Y240118D03*
Y236968D03*
Y645630D03*
Y642480D03*
Y661378D03*
Y658228D03*
Y655079D03*
Y651929D03*
Y648779D03*
Y1060591D03*
Y1057441D03*
Y1054291D03*
Y1051142D03*
Y1047992D03*
Y1066890D03*
Y1063740D03*
Y1472402D03*
Y1469252D03*
Y1466103D03*
Y1462953D03*
Y1459803D03*
Y1456654D03*
Y1453504D03*
Y1877914D03*
Y1874764D03*
Y1871615D03*
Y1868465D03*
Y1865315D03*
Y1862166D03*
Y1859016D03*
G54D40*
X14700Y1097500D03*
Y1102500D03*
X236699Y76550D03*
X889700Y1721500D03*
X952699Y89550D03*
G54D31*
X46800Y412300D03*
X42900Y604800D03*
X30499Y1592060D03*
X23999Y1968250D03*
X31999Y1922250D03*
X27999Y1968250D03*
X174999Y74750D03*
X141499Y443813D03*
X146499D03*
X159199Y520550D03*
X167199D03*
X174199D03*
X136000Y532200D03*
X170499Y812313D03*
X166499D03*
X167499Y836813D03*
X172499D03*
X119000Y1136700D03*
X119499Y1109750D03*
X100500Y1107200D03*
X109499Y1201813D03*
X105499D03*
X106999Y1227313D03*
X111999D03*
X103999Y1472000D03*
X111499D03*
X115599Y1471950D03*
X152600Y1684600D03*
X135999Y1706750D03*
X131999D03*
X209499Y101250D03*
X217499D03*
X201499D03*
X185499Y120750D03*
X188000Y424200D03*
X211500Y822700D03*
X203500D03*
X184600Y1376500D03*
X180500D03*
X192800Y1654500D03*
X223436Y1897065D03*
X315000Y373700D03*
X313500Y1973700D03*
X644049Y1796334D03*
Y1807334D03*
X752978Y339124D03*
X751196Y738582D03*
X751499Y1143750D03*
X753827Y1546996D03*
X710549Y1801334D03*
X708549Y1812034D03*
X751000Y1950700D03*
X816499Y162750D03*
X823999D03*
X831499D03*
X765000Y355700D03*
X771500Y341200D03*
X826100Y670100D03*
X766000Y754700D03*
X770000Y742200D03*
X763000Y1158700D03*
X769500Y1145200D03*
X772000Y1549200D03*
X766500Y1561700D03*
X833499Y1783750D03*
X814999D03*
X824499D03*
X828000Y1884700D03*
X765000Y1964200D03*
X770000Y1952700D03*
X916499Y111750D03*
X900499Y88250D03*
X903499Y131750D03*
X940499Y111750D03*
X944499D03*
X924499D03*
X932499D03*
X952499D03*
G54D13*
X12560Y231121D03*
Y227184D03*
Y223247D03*
Y211435D03*
Y207498D03*
Y203561D03*
Y199624D03*
Y195687D03*
Y191750D03*
Y187813D03*
Y183876D03*
Y179939D03*
Y176002D03*
Y172065D03*
Y246869D03*
Y242932D03*
Y238995D03*
Y235058D03*
X12569Y372041D03*
Y375978D03*
Y379915D03*
Y383852D03*
Y387789D03*
Y391726D03*
Y395663D03*
Y399600D03*
Y403537D03*
Y407474D03*
Y411411D03*
Y431098D03*
Y427161D03*
Y423223D03*
Y435035D03*
Y438972D03*
Y442909D03*
Y446846D03*
Y450783D03*
Y454720D03*
Y458657D03*
Y462594D03*
Y466531D03*
Y470468D03*
Y474405D03*
Y478342D03*
Y482279D03*
Y486216D03*
Y490153D03*
Y494090D03*
Y498027D03*
Y501964D03*
Y505901D03*
Y509838D03*
Y513775D03*
Y517712D03*
Y521649D03*
Y525586D03*
Y529523D03*
Y533460D03*
Y537397D03*
Y541334D03*
Y545271D03*
Y549208D03*
Y553145D03*
Y557082D03*
Y561019D03*
Y564956D03*
Y568893D03*
Y572830D03*
Y576767D03*
Y580704D03*
Y584641D03*
Y588578D03*
Y592515D03*
Y596452D03*
Y600389D03*
Y604326D03*
Y608263D03*
Y612200D03*
Y616137D03*
Y620074D03*
Y624011D03*
Y627948D03*
Y631885D03*
Y635822D03*
Y639759D03*
Y643696D03*
Y647633D03*
Y651570D03*
Y655507D03*
Y659444D03*
Y671255D03*
Y667318D03*
Y663381D03*
Y675192D03*
Y679129D03*
Y683066D03*
Y690940D03*
Y687003D03*
Y694877D03*
Y698814D03*
X12560Y813010D03*
Y809073D03*
Y805136D03*
Y801199D03*
Y797262D03*
Y793325D03*
Y789388D03*
Y785451D03*
Y781514D03*
Y856318D03*
Y852381D03*
Y848444D03*
Y844507D03*
Y840570D03*
Y836633D03*
Y832696D03*
Y820884D03*
Y816947D03*
Y1223247D03*
Y1219310D03*
Y1215373D03*
Y1211436D03*
Y1207499D03*
Y1195687D03*
Y1191750D03*
Y1187813D03*
Y1183876D03*
Y1179939D03*
Y1176002D03*
Y1172065D03*
Y1168128D03*
Y1164191D03*
Y1160254D03*
Y1156317D03*
Y1231121D03*
Y1227184D03*
X12569Y1356293D03*
Y1360230D03*
Y1364167D03*
Y1368104D03*
Y1372041D03*
Y1375978D03*
Y1379915D03*
Y1383852D03*
Y1387789D03*
Y1391726D03*
Y1395663D03*
Y1415350D03*
Y1411413D03*
Y1407475D03*
Y1419287D03*
Y1423224D03*
Y1427161D03*
Y1431098D03*
Y1435035D03*
Y1438972D03*
Y1442909D03*
Y1446846D03*
Y1450783D03*
Y1454720D03*
Y1458657D03*
Y1462594D03*
Y1466531D03*
Y1470468D03*
Y1474405D03*
Y1478342D03*
Y1482279D03*
Y1486216D03*
Y1490153D03*
Y1494090D03*
Y1498027D03*
Y1501964D03*
Y1505901D03*
Y1509838D03*
Y1513775D03*
Y1517712D03*
Y1521649D03*
Y1525586D03*
Y1529523D03*
Y1533460D03*
Y1537397D03*
Y1541334D03*
Y1545271D03*
Y1549208D03*
Y1553145D03*
Y1557082D03*
Y1561019D03*
Y1564956D03*
Y1568893D03*
Y1572830D03*
Y1576767D03*
Y1580704D03*
Y1584641D03*
Y1588578D03*
Y1592515D03*
Y1596452D03*
Y1600389D03*
Y1604326D03*
Y1608263D03*
Y1612200D03*
Y1616137D03*
Y1620074D03*
Y1624011D03*
Y1627948D03*
Y1631885D03*
Y1635822D03*
Y1639759D03*
Y1643696D03*
Y1655507D03*
Y1651570D03*
Y1647633D03*
Y1659444D03*
Y1663381D03*
Y1667318D03*
Y1675192D03*
Y1671255D03*
Y1679129D03*
Y1683066D03*
X12560Y1805136D03*
Y1801199D03*
Y1797262D03*
Y1793325D03*
Y1789388D03*
Y1785451D03*
Y1781514D03*
Y1777577D03*
Y1773640D03*
Y1769703D03*
Y1765766D03*
Y1840570D03*
Y1836633D03*
Y1832696D03*
Y1828759D03*
Y1824822D03*
Y1820885D03*
Y1816948D03*
G54D14*
X13700Y1117000D03*
Y1109000D03*
X27300Y134000D03*
X19700D03*
X27300Y126000D03*
X19700D03*
X51700Y739000D03*
X59300D03*
X21300Y1117000D03*
Y1109000D03*
X104099Y1597150D03*
X111699D03*
X232199Y33550D03*
X239799D03*
X232199Y51550D03*
X239799D03*
X232199Y42550D03*
X239799D03*
X232199Y60550D03*
X239799D03*
X232199Y69550D03*
X239799D03*
X951199Y46050D03*
X958799D03*
X951199Y64050D03*
X958799D03*
X951199Y55050D03*
X958799D03*
X949199Y101550D03*
X956799D03*
X951199Y73050D03*
X958799D03*
X951199Y82050D03*
X958799D03*
G54D41*
X84999Y1121050D03*
Y1126050D03*
Y1131050D03*
Y1136050D03*
X173999Y430050D03*
Y435050D03*
Y440050D03*
Y445050D03*
X104999Y1136050D03*
Y1131050D03*
Y1126050D03*
Y1121050D03*
X158499Y1226113D03*
Y1221113D03*
Y1216113D03*
X138499D03*
Y1221113D03*
Y1226113D03*
X158499Y1231113D03*
X138499D03*
X168499Y1625613D03*
Y1630613D03*
Y1635613D03*
Y1640613D03*
X253998Y295114D03*
Y300114D03*
Y305114D03*
Y310114D03*
X193999Y445050D03*
Y440050D03*
Y435050D03*
Y430050D03*
X254499Y701550D03*
Y706550D03*
Y711550D03*
Y716550D03*
X218499Y843613D03*
Y838613D03*
Y833613D03*
Y828613D03*
X198499D03*
Y833613D03*
Y838613D03*
Y843613D03*
X252999Y1513050D03*
Y1518050D03*
Y1523050D03*
Y1528050D03*
X188499Y1640613D03*
Y1635613D03*
Y1630613D03*
Y1625613D03*
X255777Y1917191D03*
Y1922191D03*
Y1927191D03*
Y1932191D03*
X273998Y310114D03*
Y305114D03*
Y300114D03*
Y295114D03*
X279999Y351050D03*
Y356050D03*
Y361050D03*
Y366050D03*
X299999D03*
Y361050D03*
Y356050D03*
Y351050D03*
X274499Y716550D03*
Y711550D03*
Y706550D03*
Y701550D03*
X280999Y757550D03*
Y762550D03*
Y767550D03*
Y772550D03*
X300999D03*
Y767550D03*
Y762550D03*
Y757550D03*
X272999Y1528050D03*
Y1523050D03*
Y1518050D03*
Y1513050D03*
X279999Y1568550D03*
Y1573550D03*
Y1578550D03*
Y1583550D03*
X299999D03*
Y1578550D03*
Y1573550D03*
Y1568550D03*
X275777Y1932191D03*
Y1927191D03*
Y1922191D03*
Y1917191D03*
X279777Y1961191D03*
Y1966191D03*
Y1971191D03*
X299777D03*
Y1966191D03*
Y1961191D03*
X279777Y1976191D03*
X299777D03*
X356499Y21550D03*
Y26550D03*
Y31550D03*
Y36550D03*
X376499D03*
Y31550D03*
Y26550D03*
Y21550D03*
X802873Y292471D03*
Y297471D03*
Y302471D03*
Y307471D03*
X822873D03*
Y302471D03*
Y297471D03*
Y292471D03*
X797978Y356924D03*
Y351924D03*
Y346924D03*
Y341924D03*
X777978D03*
Y346924D03*
Y351924D03*
Y356924D03*
X800831Y696853D03*
Y701853D03*
Y706853D03*
Y711853D03*
X820831D03*
Y706853D03*
Y701853D03*
Y696853D03*
X796696Y757382D03*
Y752382D03*
Y747382D03*
Y742382D03*
X776696D03*
Y747382D03*
Y752382D03*
Y757382D03*
X800841Y1101216D03*
Y1106216D03*
Y1111216D03*
Y1116216D03*
X820841D03*
Y1111216D03*
Y1106216D03*
Y1101216D03*
X796833Y1143892D03*
X776833D03*
X796833Y1158892D03*
Y1153892D03*
Y1148892D03*
X776833D03*
Y1153892D03*
Y1158892D03*
X802245Y1503722D03*
Y1508722D03*
Y1513722D03*
Y1518722D03*
X822245D03*
Y1513722D03*
Y1508722D03*
Y1503722D03*
X799327Y1553796D03*
Y1548796D03*
X779327D03*
Y1553796D03*
X799327Y1563796D03*
Y1558796D03*
X779327D03*
Y1563796D03*
X801436Y1910365D03*
Y1915365D03*
Y1920365D03*
Y1925365D03*
X821436D03*
Y1920365D03*
Y1915365D03*
Y1910365D03*
X796814Y1969713D03*
Y1964713D03*
Y1959713D03*
Y1954713D03*
X776814D03*
Y1959713D03*
Y1964713D03*
Y1969713D03*
G54D23*
X71773Y209631D03*
Y206431D03*
X66023Y209631D03*
Y206431D03*
X71773Y615143D03*
Y611943D03*
X66023Y615143D03*
Y611943D03*
X71773Y1020655D03*
Y1017455D03*
X66023Y1020655D03*
Y1017455D03*
X71773Y1426167D03*
Y1422967D03*
X66023Y1426167D03*
Y1422967D03*
X71773Y1831679D03*
Y1828479D03*
X66023Y1831679D03*
Y1828479D03*
X164448Y160447D03*
Y163647D03*
X170198Y160447D03*
Y163647D03*
X164448Y565959D03*
Y569159D03*
X170198Y565959D03*
Y569159D03*
X164448Y971471D03*
Y974671D03*
X170198Y971471D03*
Y974671D03*
X164448Y1376983D03*
Y1380183D03*
X170198Y1376983D03*
Y1380183D03*
X164448Y1782494D03*
Y1785694D03*
X170198Y1782494D03*
Y1785694D03*
X892794Y160447D03*
Y163647D03*
X898544Y160447D03*
Y163647D03*
X892794Y565959D03*
Y569159D03*
X898544Y565959D03*
Y569159D03*
X892794Y971471D03*
Y974671D03*
X898544Y971471D03*
Y974671D03*
X892794Y1376983D03*
Y1380183D03*
X898544Y1376983D03*
Y1380183D03*
X892794Y1782494D03*
Y1785694D03*
X898544Y1782494D03*
Y1785694D03*
G54D50*
X18499Y1929350D03*
X134300Y460600D03*
X139499Y494413D03*
X162499Y891913D03*
X162999Y858413D03*
X104499Y1273413D03*
X103999Y1240850D03*
X105499Y1678913D03*
X102100Y1644300D03*
X221498Y286914D03*
X221499Y693350D03*
X217500Y1089800D03*
X253200Y1540500D03*
X220999Y1503350D03*
X227814Y1896913D03*
X293999Y61913D03*
X289099Y28913D03*
X853978Y280724D03*
X852696Y681682D03*
X852333Y1087192D03*
X854327Y1492096D03*
X894800Y1709800D03*
X854814Y1897913D03*
G54D32*
X46800Y408900D03*
X42900Y601400D03*
X30499Y1588660D03*
X23999Y1964850D03*
X31999Y1918850D03*
X27999Y1964850D03*
X174999Y71350D03*
X141499Y440413D03*
X146499D03*
X159199Y517150D03*
X167199D03*
X174199D03*
X136000Y528800D03*
X170499Y808913D03*
X166499D03*
X167499Y833413D03*
X172499D03*
X119000Y1133300D03*
X119499Y1106350D03*
X100500Y1103800D03*
X106999Y1223913D03*
X111999D03*
X109499Y1198413D03*
X105499D03*
X103999Y1468600D03*
X111499D03*
X115599Y1468550D03*
X152600Y1681200D03*
X135999Y1703350D03*
X131999D03*
X209499Y97850D03*
X217499D03*
X201499D03*
X185499Y117350D03*
X188000Y420800D03*
X211500Y819300D03*
X203500D03*
X184600Y1373100D03*
X180500D03*
X192800Y1651100D03*
X223436Y1893665D03*
X315000Y370300D03*
X313500Y1970300D03*
X644049Y1803934D03*
Y1792934D03*
X752978Y335724D03*
X751196Y735182D03*
X751499Y1140350D03*
X753827Y1543596D03*
X710549Y1797934D03*
X708549Y1808634D03*
X751000Y1947300D03*
X816499Y159350D03*
X823999D03*
X831499D03*
X765000Y352300D03*
X771500Y337800D03*
X826100Y666700D03*
X766000Y751300D03*
X770000Y738800D03*
X769500Y1141800D03*
X763000Y1155300D03*
X772000Y1545800D03*
X766500Y1558300D03*
X833499Y1780350D03*
X814999D03*
X824499D03*
X828000Y1881300D03*
X765000Y1960800D03*
X770000Y1949300D03*
X916499Y108350D03*
X900499Y84850D03*
X903499Y128350D03*
X940499Y108350D03*
X944499D03*
X924499D03*
X932499D03*
X952499D03*
G54D33*
X42700Y408900D03*
X34000Y1058300D03*
X83000Y1548300D03*
X79000D03*
X34599Y1588650D03*
X75000Y1565200D03*
X79000D03*
X31999Y1964850D03*
X19999D03*
X27030Y1925238D03*
X49499Y1901850D03*
X23030Y1925238D03*
X31999Y1972350D03*
X162999Y443913D03*
X150999Y440413D03*
X176499Y833413D03*
X127000Y1133300D03*
X100500Y1111800D03*
X97499Y1086850D03*
X101999D03*
X127499Y1224413D03*
X116499Y1223913D03*
Y1321413D03*
X120507Y1321496D03*
X116749Y1510150D03*
X112599D03*
X174499Y1649663D03*
X205499Y97850D03*
X197499D03*
X185999Y496450D03*
X181899D03*
X185999Y842413D03*
X190499D03*
X205999Y898313D03*
X209999D03*
X226800Y1086600D03*
X247500Y1078550D03*
X225499Y1499350D03*
X203000Y1637800D03*
X231000Y1880500D03*
X236100Y1893900D03*
X307000Y370300D03*
X280499Y341850D03*
X284999D03*
X311000Y771300D03*
X281499Y748350D03*
X285499D03*
X310500Y1582800D03*
X278499Y1559350D03*
X282499D03*
X330000Y1969800D03*
X284358Y1951628D03*
X288358D03*
X363000Y42800D03*
X399999Y39350D03*
X640049Y1803934D03*
Y1792934D03*
X649049Y1810934D03*
X655549Y1815434D03*
X749500Y348300D03*
X750500Y747800D03*
X747500Y1151800D03*
X751000Y1553800D03*
X744049Y1802934D03*
Y1795434D03*
X706549Y1797934D03*
X744049Y1810434D03*
X712549Y1808634D03*
X749500Y1958300D03*
X833999Y204850D03*
X829499D03*
X827500Y267500D03*
X825700Y1075800D03*
X827700Y1480700D03*
X912499Y108350D03*
X920499D03*
X889700Y1704700D03*
X936499Y108350D03*
X948499D03*
G54D51*
X37999Y1968750D03*
X65768Y1966462D03*
X74568D03*
X83568D03*
X57068D03*
X92568D03*
X37999Y1976350D03*
X65768Y1974062D03*
X74568D03*
X83568D03*
X57068D03*
X92568D03*
X240999Y89850D03*
Y82250D03*
G54D15*
X17720Y1903144D03*
X29532Y309561D03*
Y1029522D03*
X129920Y17716D03*
X271657Y267711D03*
Y673223D03*
Y1078734D03*
Y1484246D03*
Y1889758D03*
X994098Y149601D03*
Y673223D03*
X994099Y1068892D03*
X994093Y1889751D03*
G54D42*
X72999Y1871550D03*
Y1882550D03*
X63999Y1871050D03*
Y1882050D03*
X169999Y123550D03*
Y112550D03*
X178999Y123550D03*
Y112550D03*
X158999Y453113D03*
Y464113D03*
X149999Y453113D03*
Y464113D03*
X140999Y453113D03*
Y464113D03*
X167900Y453100D03*
Y464100D03*
X146499Y486613D03*
Y497613D03*
X178999Y851613D03*
Y862613D03*
X169999Y851613D03*
Y862613D03*
X169499Y885113D03*
Y896113D03*
X129900Y1182500D03*
Y1171500D03*
X102999Y1182550D03*
Y1171550D03*
X111999Y1182550D03*
Y1171550D03*
X120999Y1182550D03*
Y1171550D03*
X132700Y1265400D03*
Y1254400D03*
X129499Y1233613D03*
Y1244613D03*
X120499Y1233613D03*
Y1244613D03*
X111499Y1233613D03*
Y1244613D03*
Y1266613D03*
Y1277613D03*
X126199Y1638013D03*
X117500Y1638000D03*
X108799Y1638013D03*
X133999Y1670613D03*
Y1659613D03*
X126199Y1649013D03*
X117500Y1649000D03*
X108799Y1649013D03*
X112499Y1671613D03*
Y1682613D03*
X225900Y307400D03*
X246498Y319114D03*
Y330114D03*
X237698Y351614D03*
Y340614D03*
X228998Y351614D03*
Y340614D03*
X220298Y351614D03*
Y340614D03*
X225900Y318400D03*
X246499Y726050D03*
X225499D03*
Y715050D03*
X246499Y737050D03*
X238699Y760550D03*
Y749550D03*
X229999Y760550D03*
Y749550D03*
X221299Y760550D03*
Y749550D03*
X191499Y884113D03*
Y873113D03*
X187999Y851613D03*
Y862613D03*
X224300Y1130200D03*
Y1119200D03*
X246499Y1535550D03*
Y1546550D03*
X237700Y1557100D03*
X229000D03*
X220300D03*
X224999Y1535550D03*
Y1524550D03*
X237700Y1568100D03*
X229000D03*
X220300D03*
X246314Y1934113D03*
Y1945113D03*
X220300Y1964600D03*
Y1953600D03*
X229000Y1964600D03*
Y1953600D03*
X237700Y1964600D03*
Y1953600D03*
X225814Y1931113D03*
Y1920113D03*
X322499Y54613D03*
Y43613D03*
X314099Y22113D03*
Y33113D03*
X305099Y22113D03*
Y33113D03*
X296099Y22113D03*
Y33113D03*
X300999Y55613D03*
Y66613D03*
X832978Y313424D03*
Y324424D03*
X840800Y346800D03*
Y335800D03*
X830499Y715550D03*
Y726550D03*
X838796Y747582D03*
Y736582D03*
X830499Y1119550D03*
Y1130550D03*
X838833Y1141392D03*
Y1152392D03*
X833827Y1523796D03*
Y1534796D03*
X841500Y1556300D03*
Y1545300D03*
X840400Y1965000D03*
Y1954000D03*
X832499Y1930050D03*
Y1941050D03*
X846999Y135550D03*
Y124550D03*
X896999Y136550D03*
Y125550D03*
X850999Y312550D03*
Y301550D03*
X849500Y346800D03*
Y335800D03*
X858200Y346800D03*
Y335800D03*
X848696Y713882D03*
Y702882D03*
X847496Y747582D03*
Y736582D03*
X856196Y747582D03*
Y736582D03*
X847533Y1141392D03*
X856233D03*
X848413Y1118613D03*
Y1107613D03*
X847533Y1152392D03*
X856233D03*
X850200Y1556300D03*
Y1545300D03*
X858900Y1556300D03*
Y1545300D03*
X850827Y1523296D03*
Y1512296D03*
X849100Y1965000D03*
Y1954000D03*
X857800Y1965000D03*
Y1954000D03*
X850314Y1929113D03*
Y1918113D03*
G54D60*
X130400Y420900D03*
X159500Y821800D03*
X177500Y1276800D03*
X122799Y1485350D03*
X178999Y74850D03*
X235499Y84850D03*
X213499Y101350D03*
X216998Y287414D03*
X184000Y424300D03*
X212000Y513300D03*
X216999Y693850D03*
X207500Y822800D03*
X222900Y1090100D03*
X216999Y1503850D03*
X253500Y1911300D03*
X232314Y1897413D03*
X327500Y354800D03*
X312800Y321100D03*
X308999Y728350D03*
X311000Y758300D03*
X309299Y1536750D03*
X313499Y1931850D03*
X366500Y86300D03*
X655549Y1796434D03*
Y1803934D03*
X755500Y709800D03*
X693549Y1801934D03*
Y1809434D03*
X816500Y286300D03*
X764500Y308300D03*
X779978Y308224D03*
X769000Y355800D03*
X810000Y690800D03*
X777500Y709800D03*
X816000Y1094300D03*
X760500Y1110800D03*
X778500D03*
X767000Y1158800D03*
X816000Y1497800D03*
X783200Y1516500D03*
X762000Y1516800D03*
X770500Y1561800D03*
X815500Y1904300D03*
X769000Y1964300D03*
X759500Y1922800D03*
X784500D03*
X904499Y88350D03*
X858478Y281224D03*
X857196Y682182D03*
X856833Y1087692D03*
X858827Y1492596D03*
X859314Y1898413D03*
X928499Y111850D03*
G54D24*
X55799Y203550D03*
X77799Y204550D03*
X55799Y207550D03*
X77799Y208550D03*
X55799Y211550D03*
X77801Y611450D03*
Y615450D03*
X31299Y611550D03*
X56299Y1017050D03*
X81300Y1008500D03*
X56236Y1021050D03*
Y1025050D03*
X73799Y1837550D03*
X82549Y1828613D03*
X74049Y1843113D03*
X82549Y1832613D03*
X73799Y1849050D03*
X18299Y1948050D03*
Y1952050D03*
Y1940050D03*
X52299Y1897050D03*
X148299Y517613D03*
X155999Y524850D03*
X163499D03*
X170999D03*
X143800Y545000D03*
X171299Y916113D03*
X105550Y972000D03*
X105499Y967850D03*
X124780Y1098482D03*
Y1094482D03*
X112799Y1298113D03*
X128300Y1361000D03*
X138700Y1335800D03*
X127799Y1342050D03*
X100549Y1476050D03*
X108049D03*
X114049Y1702613D03*
X170800Y1691200D03*
X230299Y105050D03*
X238299Y95550D03*
X230172Y92572D03*
X179472Y90572D03*
Y86572D03*
X183199Y152000D03*
X226298Y287114D03*
X240600Y269700D03*
X183199Y559300D03*
X226299Y693550D03*
X240000Y677100D03*
X183699Y963100D03*
X199199Y1367400D03*
X182699Y1773200D03*
X302299Y86613D03*
X316200Y105200D03*
X305299Y334050D03*
Y339050D03*
X329798Y337114D03*
Y333114D03*
X315000Y365200D03*
X312300Y779000D03*
X306799Y742050D03*
Y746050D03*
X331299Y745050D03*
Y741050D03*
X316000Y772200D03*
X303299Y1554550D03*
X327799Y1557550D03*
Y1553550D03*
X312800Y1591000D03*
X314800Y1587000D03*
X303299Y1558550D03*
X315000Y1582600D03*
X310521Y1944909D03*
Y1948909D03*
X336021Y1947409D03*
Y1943409D03*
X318200Y1971900D03*
X370800Y46500D03*
X375400Y42300D03*
X751278Y323924D03*
Y328924D03*
X749996Y724882D03*
Y729882D03*
X750633Y1126392D03*
Y1131392D03*
X753627Y1531296D03*
Y1536296D03*
X697349Y1801634D03*
Y1808634D03*
X750114Y1937713D03*
Y1942213D03*
X813299Y167050D03*
X820799D03*
X828299D03*
X797299Y336050D03*
Y332050D03*
X776299Y326550D03*
Y322550D03*
X774299Y724050D03*
Y728550D03*
X795799Y736050D03*
Y732050D03*
Y1133050D03*
Y1137050D03*
X775299Y1127550D03*
Y1123550D03*
X798481Y1538893D03*
Y1542893D03*
X777481Y1527893D03*
Y1531893D03*
X813799Y1788050D03*
X821299D03*
X828799D03*
X796981Y1944393D03*
Y1948393D03*
X774799Y1935050D03*
Y1939050D03*
X902299Y103050D03*
Y107050D03*
X845800Y276800D03*
X912699Y557800D03*
X844500Y677700D03*
X913199Y962100D03*
X844100Y1083200D03*
X869799Y1359550D03*
Y1367550D03*
Y1363550D03*
X846100Y1488100D03*
X912699Y1771700D03*
X846599Y1893850D03*
X927699Y158500D03*
G54D34*
X42700Y412300D03*
X34000Y1061700D03*
X83000Y1551700D03*
X79000D03*
X34599Y1592050D03*
X75000Y1568600D03*
X79000D03*
X31999Y1968250D03*
X19999D03*
X27030Y1928638D03*
X49499Y1905250D03*
X23030Y1928638D03*
X31999Y1975750D03*
X162999Y447313D03*
X150999Y443813D03*
X176499Y836813D03*
X127000Y1136700D03*
X100500Y1115200D03*
X97499Y1090250D03*
X101999D03*
X127499Y1227813D03*
X116499Y1227313D03*
Y1324813D03*
X120507Y1324896D03*
X116749Y1513550D03*
X112599D03*
X174499Y1653063D03*
X205499Y101250D03*
X197499D03*
X185999Y499850D03*
X181899D03*
X185999Y845813D03*
X190499D03*
X205999Y901713D03*
X209999D03*
X226800Y1090000D03*
X247500Y1081950D03*
X225499Y1502750D03*
X203000Y1641200D03*
X231000Y1883900D03*
X236100Y1897300D03*
X307000Y373700D03*
X280499Y345250D03*
X284999D03*
X311000Y774700D03*
X281499Y751750D03*
X285499D03*
X310500Y1586200D03*
X278499Y1562750D03*
X282499D03*
X284358Y1955028D03*
X288358D03*
X330000Y1973200D03*
X363000Y46200D03*
X399999Y42750D03*
X640049Y1796334D03*
X649049Y1814334D03*
X655549Y1818834D03*
X640049Y1807334D03*
X749500Y351700D03*
X750500Y751200D03*
X747500Y1155200D03*
X751000Y1557200D03*
X744049Y1798834D03*
X706549Y1801334D03*
X744049Y1813834D03*
Y1806334D03*
X712549Y1812034D03*
X749500Y1961700D03*
X833999Y208250D03*
X829499D03*
X827500Y270900D03*
X825700Y1079200D03*
X827700Y1484100D03*
X912499Y111750D03*
X920499D03*
X889700Y1708100D03*
X936499Y111750D03*
X948499D03*
G54D43*
X43999Y1964750D03*
X138999Y517313D03*
X161999Y915813D03*
X123000Y1133200D03*
X142667Y1306460D03*
X132999Y1306813D03*
X103499Y1297813D03*
X178500Y1697700D03*
X104999Y1702063D03*
X137504Y1735523D03*
X123999Y1734813D03*
X182499Y71250D03*
X194500Y499200D03*
X236000Y908200D03*
X215900Y896900D03*
X199000Y1637700D03*
X292999Y86313D03*
X311000Y370200D03*
X295500Y329200D03*
X307000Y771200D03*
X298000Y735700D03*
X297000Y1549800D03*
X327000Y1570700D03*
X306500Y1582700D03*
X309300Y1970276D03*
X296858Y1944028D03*
X367000Y42700D03*
X389500Y72200D03*
X369300Y72300D03*
X693549Y1813334D03*
X770000Y751200D03*
X907999Y84750D03*
X870201Y1709850D03*
G54D52*
X44368Y1946712D03*
G54D70*
X105749Y1964050D03*
X121249D03*
X221749Y39550D03*
X206249D03*
X915749Y44550D03*
X931249D03*
G54D25*
X59199Y203550D03*
X81199Y204550D03*
X59199Y207550D03*
X81199Y208550D03*
X59199Y211550D03*
X81201Y611450D03*
Y615450D03*
X34699Y611550D03*
X59699Y1017050D03*
X84700Y1008500D03*
X59636Y1021050D03*
Y1025050D03*
X77199Y1837550D03*
X85949Y1828613D03*
X77449Y1843113D03*
X85949Y1832613D03*
X77199Y1849050D03*
X21699Y1948050D03*
Y1952050D03*
Y1940050D03*
X55699Y1897050D03*
X151699Y517613D03*
X159399Y524850D03*
X166899D03*
X174399D03*
X147200Y545000D03*
X174699Y916113D03*
X108950Y972000D03*
X108899Y967850D03*
X128180Y1098482D03*
Y1094482D03*
X116199Y1298113D03*
X131700Y1361000D03*
X142100Y1335800D03*
X131199Y1342050D03*
X103949Y1476050D03*
X111449D03*
X117449Y1702613D03*
X174200Y1691200D03*
X233699Y105050D03*
X241699Y95550D03*
X233572Y92572D03*
X182872Y90572D03*
Y86572D03*
X186599Y152000D03*
X229698Y287114D03*
X244000Y269700D03*
X186599Y559300D03*
X229699Y693550D03*
X243400Y677100D03*
X187099Y963100D03*
X202599Y1367400D03*
X186099Y1773200D03*
X305699Y86613D03*
X319600Y105200D03*
X308699Y334050D03*
Y339050D03*
X333198Y337114D03*
Y333114D03*
X318400Y365200D03*
X315700Y779000D03*
X310199Y742050D03*
Y746050D03*
X334699Y745050D03*
Y741050D03*
X319400Y772200D03*
X306699Y1554550D03*
X331199Y1557550D03*
Y1553550D03*
X316200Y1591000D03*
X318200Y1587000D03*
X306699Y1558550D03*
X318400Y1582600D03*
X313921Y1944909D03*
Y1948909D03*
X339421Y1947409D03*
Y1943409D03*
X321600Y1971900D03*
X374200Y46500D03*
X378800Y42300D03*
X754678Y323924D03*
Y328924D03*
X753396Y724882D03*
Y729882D03*
X754033Y1126392D03*
Y1131392D03*
X757027Y1531296D03*
Y1536296D03*
X700749Y1801634D03*
Y1808634D03*
X753514Y1937713D03*
Y1942213D03*
X816699Y167050D03*
X824199D03*
X831699D03*
X800699Y336050D03*
Y332050D03*
X779699Y326550D03*
Y322550D03*
X777699Y724050D03*
Y728550D03*
X799199Y736050D03*
Y732050D03*
Y1133050D03*
Y1137050D03*
X778699Y1127550D03*
Y1123550D03*
X801881Y1538893D03*
Y1542893D03*
X780881Y1527893D03*
Y1531893D03*
X817199Y1788050D03*
X824699D03*
X832199D03*
X800381Y1944393D03*
Y1948393D03*
X778199Y1935050D03*
Y1939050D03*
X905699Y103050D03*
Y107050D03*
X849200Y276800D03*
X916099Y557800D03*
X847900Y677700D03*
X916599Y962100D03*
X847500Y1083200D03*
X873199Y1359550D03*
Y1367550D03*
Y1363550D03*
X849500Y1488100D03*
X916099Y1771700D03*
X849999Y1893850D03*
X931099Y158500D03*
G54D61*
X130400Y417300D03*
X159500Y818200D03*
X177500Y1273200D03*
X122799Y1481750D03*
X178999Y71250D03*
X235499Y81250D03*
X213499Y97750D03*
X216998Y283814D03*
X184000Y420700D03*
X212000Y509700D03*
X216999Y690250D03*
X207500Y819200D03*
X222900Y1086500D03*
X216999Y1500250D03*
X253500Y1907700D03*
X232314Y1893813D03*
X327500Y351200D03*
X312800Y317500D03*
X308999Y724750D03*
X311000Y754700D03*
X309299Y1533150D03*
X313499Y1928250D03*
X366500Y82700D03*
X655549Y1792834D03*
Y1800334D03*
X755500Y706200D03*
X693549Y1798334D03*
Y1805834D03*
X816500Y282700D03*
X764500Y304700D03*
X779978Y304624D03*
X769000Y352200D03*
X810000Y687200D03*
X777500Y706200D03*
X816000Y1090700D03*
X760500Y1107200D03*
X778500D03*
X767000Y1155200D03*
X816000Y1494200D03*
X783200Y1512900D03*
X762000Y1513200D03*
X770500Y1558200D03*
X815500Y1900700D03*
X769000Y1960700D03*
X759500Y1919200D03*
X784500D03*
X904499Y84750D03*
X858478Y277624D03*
X857196Y678582D03*
X856833Y1084092D03*
X858827Y1488996D03*
X859314Y1894813D03*
X928499Y108250D03*
G54D16*
X68898Y17047D03*
Y190275D03*
Y422559D03*
Y595787D03*
Y828071D03*
Y1001299D03*
Y1233583D03*
Y1406811D03*
Y1639095D03*
Y1812323D03*
X167323Y179803D03*
Y353031D03*
Y585315D03*
Y758543D03*
Y990827D03*
Y1164055D03*
Y1396339D03*
Y1569567D03*
Y1801851D03*
Y1975079D03*
X895669Y179803D03*
Y353031D03*
Y585315D03*
Y758543D03*
Y990827D03*
Y1164055D03*
Y1396339D03*
Y1569567D03*
Y1801851D03*
Y1975079D03*
G54D26*
X51799Y217100D03*
X48400Y635500D03*
X34699Y616050D03*
X48400Y639600D03*
X79199Y642550D03*
X38800Y607326D03*
Y603200D03*
X35500Y597400D03*
Y593300D03*
X43100Y597400D03*
X60449Y656487D03*
Y652487D03*
Y648487D03*
X82700Y1013000D03*
X87299Y1000450D03*
Y1004450D03*
X92700Y1557500D03*
Y1553500D03*
X41699Y1838050D03*
Y1842050D03*
X67299Y1851900D03*
X21699Y1944050D03*
Y1936050D03*
X158199Y165050D03*
Y161050D03*
X170300Y420300D03*
X137699Y423113D03*
Y427113D03*
X170300Y424300D03*
X157499Y540050D03*
Y544250D03*
X157699Y570050D03*
Y566050D03*
X158199Y975550D03*
Y971550D03*
X174700Y922700D03*
X122199Y1125050D03*
X101299Y1081700D03*
Y1077400D03*
X143200Y1202000D03*
X139700Y1210000D03*
X134700Y1202000D03*
Y1206000D03*
X123199Y1356050D03*
Y1352050D03*
X131700Y1365000D03*
X123699Y1343050D03*
X128000Y1319900D03*
X118949Y1476050D03*
X147699Y1722550D03*
Y1718550D03*
X109199Y1716613D03*
Y1720613D03*
X158171Y1786909D03*
Y1782909D03*
X233699Y101050D03*
X182826Y82428D03*
X233699Y97050D03*
X180199Y165050D03*
Y161050D03*
Y156550D03*
X232100Y283000D03*
X179700Y420500D03*
X180199Y564050D03*
Y572050D03*
Y568050D03*
X229700Y689500D03*
X198800Y823000D03*
X179949Y976550D03*
Y972550D03*
X180199Y967550D03*
X183800Y931600D03*
X227950Y1082500D03*
X194699Y1381050D03*
Y1377050D03*
Y1373050D03*
X228200Y1480100D03*
X233100Y1499300D03*
X198749Y1630613D03*
X206700Y1649500D03*
X202200Y1645500D03*
X180764Y1786613D03*
Y1782613D03*
Y1778613D03*
X337699Y63050D03*
Y67050D03*
X305700Y90700D03*
X310199Y360050D03*
Y356050D03*
X308699Y343550D03*
X311199Y767050D03*
Y762550D03*
X310199Y750050D03*
Y1573050D03*
X306699Y1562550D03*
X313477Y1966191D03*
Y1962191D03*
X313558Y1953328D03*
X404199Y56050D03*
X386699Y30550D03*
Y26050D03*
X404199Y51050D03*
X378699Y53050D03*
Y57050D03*
X651749Y1803634D03*
Y1796134D03*
X651249Y1818634D03*
X757200Y351500D03*
X755200Y1154500D03*
X739749Y1798634D03*
Y1814134D03*
Y1806634D03*
X697249Y1821634D03*
Y1825634D03*
X757200Y1961000D03*
X760700Y355500D03*
X761700Y755000D03*
X758200Y751000D03*
X758700Y1158500D03*
Y1556500D03*
X762200Y1561000D03*
X789249Y1804634D03*
Y1800634D03*
X817199Y1825550D03*
Y1821550D03*
X777749Y1817634D03*
X760700Y1965000D03*
X905699Y99050D03*
X874928Y163924D03*
Y159924D03*
X849178Y280924D03*
X908646Y562882D03*
Y570882D03*
X886699Y570550D03*
X908646Y566882D03*
X886699Y565050D03*
X847896Y681882D03*
X908533Y974392D03*
X886533Y975892D03*
X908533Y970392D03*
X886533Y971892D03*
X908533Y966392D03*
X847533Y1087392D03*
X873527Y1379796D03*
Y1375796D03*
X861799Y1372200D03*
X849527Y1492296D03*
X908264Y1785613D03*
X886300Y1786300D03*
X908264Y1781613D03*
X886264Y1782213D03*
X908264Y1777613D03*
X881301Y1727450D03*
X888801D03*
X850014Y1898113D03*
X925928Y168424D03*
Y164424D03*
X925699Y172550D03*
G54D44*
X43999Y1968350D03*
X138999Y520913D03*
X161999Y919413D03*
X123000Y1136800D03*
X103499Y1301413D03*
X142667Y1310060D03*
X132999Y1310413D03*
X178500Y1701300D03*
X104999Y1705663D03*
X137504Y1739123D03*
X123999Y1738413D03*
X182499Y74850D03*
X194500Y502800D03*
X236000Y911800D03*
X215900Y900500D03*
X199000Y1641300D03*
X292999Y89913D03*
X311000Y373800D03*
X295500Y332800D03*
X307000Y774800D03*
X298000Y739300D03*
X297000Y1553400D03*
X327000Y1574300D03*
X306500Y1586300D03*
X296858Y1947628D03*
X309300Y1973876D03*
X367000Y46300D03*
X389500Y75800D03*
X369300Y75900D03*
X693549Y1816934D03*
X770000Y754800D03*
X907999Y88350D03*
X870201Y1713450D03*
G54D35*
X69400Y719500D03*
X44600D03*
X91099Y1890550D03*
Y1870050D03*
X125300Y1582500D03*
X100500D03*
X115899Y1890550D03*
Y1870050D03*
G54D80*
X825300Y1726200D03*
X836300D03*
X887700Y1733800D03*
X876700D03*
X940400Y1486900D03*
X951400D03*
X940500Y1477500D03*
X951500D03*
G54D53*
X34525Y1956355D03*
X36494D03*
X38462D03*
X40431D03*
X42399D03*
X44368D03*
X46337D03*
X48305D03*
X50274D03*
X52242D03*
X54211D03*
Y1937069D03*
X52242D03*
X50274D03*
X48305D03*
X46337D03*
X44368D03*
X42399D03*
X40431D03*
X38462D03*
X36494D03*
X34525D03*
G54D62*
X158299Y438173D03*
Y435613D03*
Y433053D03*
X165699D03*
Y435613D03*
Y438173D03*
X113499Y1106640D03*
Y1109200D03*
Y1111760D03*
X106099D03*
Y1109200D03*
Y1106640D03*
X123299Y1218673D03*
Y1216113D03*
Y1213553D03*
X130699D03*
Y1216113D03*
Y1218673D03*
X147400Y1324540D03*
Y1327100D03*
Y1329660D03*
X140000D03*
Y1327100D03*
Y1324540D03*
X181799Y836673D03*
Y834113D03*
Y831553D03*
X189199D03*
Y834113D03*
Y836673D03*
X242000Y1069000D03*
Y1071560D03*
Y1074120D03*
X234600D03*
Y1071560D03*
Y1069000D03*
X233600Y1473240D03*
X241000D03*
X233600Y1478360D03*
Y1475800D03*
X241000D03*
Y1478360D03*
X179999Y1652987D03*
Y1650427D03*
Y1647867D03*
X187399D03*
Y1650427D03*
Y1652987D03*
X218100Y1882960D03*
Y1880400D03*
Y1877840D03*
X225500D03*
Y1880400D03*
Y1882960D03*
X324800Y92340D03*
Y94900D03*
Y97460D03*
X317400D03*
Y94900D03*
Y92340D03*
X394199Y36490D03*
Y39050D03*
Y41610D03*
X386799D03*
Y39050D03*
Y36490D03*
X758778Y341984D03*
Y339424D03*
Y336864D03*
X756996Y742442D03*
Y739882D03*
Y737322D03*
X756799Y1141490D03*
Y1146610D03*
Y1144050D03*
X757114Y1954773D03*
Y1952213D03*
Y1949653D03*
X814700Y270060D03*
Y267500D03*
Y264940D03*
X822100D03*
Y267500D03*
Y270060D03*
X766178Y336864D03*
Y339424D03*
Y341984D03*
X813200Y672660D03*
Y670100D03*
Y667540D03*
X820600D03*
Y670100D03*
Y672660D03*
X764396Y737322D03*
Y739882D03*
Y742442D03*
X764199Y1141490D03*
X812900Y1075460D03*
Y1072900D03*
Y1070340D03*
X820300D03*
Y1072900D03*
Y1075460D03*
X764199Y1144050D03*
Y1146610D03*
X759127Y1549356D03*
Y1546796D03*
Y1544236D03*
X766527D03*
Y1546796D03*
Y1549356D03*
X814700Y1483160D03*
Y1480600D03*
Y1478040D03*
X822100D03*
Y1480600D03*
Y1483160D03*
X815300Y1887560D03*
Y1885000D03*
Y1882440D03*
X822700D03*
Y1885000D03*
Y1887560D03*
X764514Y1949653D03*
Y1952213D03*
Y1954773D03*
G54D71*
X210676Y72528D03*
X928499Y85550D03*
G54D17*
X78150Y28858D03*
Y178464D03*
Y434370D03*
Y583976D03*
Y839882D03*
Y989488D03*
Y1245394D03*
Y1395000D03*
Y1650906D03*
Y1800512D03*
X158071Y191614D03*
Y341220D03*
Y597126D03*
Y746732D03*
Y1002638D03*
Y1152244D03*
Y1408150D03*
Y1557756D03*
Y1813662D03*
Y1963268D03*
X886417Y191614D03*
Y341220D03*
Y597126D03*
Y746732D03*
Y1002638D03*
Y1152244D03*
Y1408150D03*
Y1557756D03*
Y1813662D03*
Y1963268D03*
G54D27*
X48399Y217100D03*
X45000Y635500D03*
X31299Y616050D03*
X45000Y639600D03*
X75799Y642550D03*
X35400Y607326D03*
Y603200D03*
X32100Y597400D03*
Y593300D03*
X39700Y597400D03*
X57049Y656487D03*
Y652487D03*
Y648487D03*
X79300Y1013000D03*
X83899Y1000450D03*
Y1004450D03*
X89300Y1557500D03*
Y1553500D03*
X38299Y1838050D03*
Y1842050D03*
X63899Y1851900D03*
X18299Y1944050D03*
Y1936050D03*
X176799Y165050D03*
X154799D03*
X176799Y161050D03*
X154799D03*
X176799Y156550D03*
X176300Y420500D03*
X166900Y420300D03*
X134299Y423113D03*
Y427113D03*
X166900Y424300D03*
X176799Y564050D03*
X154099Y540050D03*
Y544250D03*
X176799Y572050D03*
X154299Y570050D03*
X176799Y568050D03*
X154299Y566050D03*
X176549Y976550D03*
X154799Y975550D03*
X176549Y972550D03*
X154799Y971550D03*
X176799Y967550D03*
X171300Y922700D03*
X118799Y1125050D03*
X97899Y1081700D03*
Y1077400D03*
X139800Y1202000D03*
X136300Y1210000D03*
X131300Y1202000D03*
Y1206000D03*
X119799Y1356050D03*
Y1352050D03*
X128300Y1365000D03*
X120299Y1343050D03*
X124600Y1319900D03*
X115549Y1476050D03*
X144299Y1722550D03*
Y1718550D03*
X105799Y1716613D03*
Y1720613D03*
X177364Y1786613D03*
X154771Y1786909D03*
X177364Y1782613D03*
X154771Y1782909D03*
X177364Y1778613D03*
X230299Y101050D03*
X179426Y82428D03*
X230299Y97050D03*
X228700Y283000D03*
X226300Y689500D03*
X195400Y823000D03*
X180400Y931600D03*
X224550Y1082500D03*
X191299Y1381050D03*
Y1377050D03*
Y1373050D03*
X224800Y1480100D03*
X229700Y1499300D03*
X195349Y1630613D03*
X203300Y1649500D03*
X198800Y1645500D03*
X334299Y63050D03*
Y67050D03*
X302300Y90700D03*
X306799Y360050D03*
Y356050D03*
X305299Y343550D03*
X307799Y767050D03*
Y762550D03*
X306799Y750050D03*
Y1573050D03*
X303299Y1562550D03*
X310077Y1966191D03*
Y1962191D03*
X310158Y1953328D03*
X400799Y56050D03*
X383299Y30550D03*
Y26050D03*
X400799Y51050D03*
X375299Y53050D03*
Y57050D03*
X648349Y1803634D03*
Y1796134D03*
X647849Y1818634D03*
X757300Y355500D03*
X753800Y351500D03*
X754800Y751000D03*
X755300Y1158500D03*
X751800Y1154500D03*
X755300Y1556500D03*
X736349Y1798634D03*
Y1814134D03*
Y1806634D03*
X693849Y1821634D03*
Y1825634D03*
X757300Y1965000D03*
X753800Y1961000D03*
X758300Y755000D03*
X758800Y1561000D03*
X785849Y1804634D03*
Y1800634D03*
X813799Y1825550D03*
Y1821550D03*
X774349Y1817634D03*
X902299Y99050D03*
X871528Y163924D03*
X922528Y168424D03*
X871528Y159924D03*
X922528Y164424D03*
X922299Y172550D03*
X845778Y280924D03*
X905246Y562882D03*
Y570882D03*
X883299Y570550D03*
X905246Y566882D03*
X883299Y565050D03*
X844496Y681882D03*
X905133Y974392D03*
X883133Y975892D03*
X905133Y970392D03*
X883133Y971892D03*
X905133Y966392D03*
X844133Y1087392D03*
X870127Y1379796D03*
Y1375796D03*
X858399Y1372200D03*
X846127Y1492296D03*
X904864Y1785613D03*
X882900Y1786300D03*
X904864Y1781613D03*
X882864Y1782213D03*
X904864Y1777613D03*
X877901Y1727450D03*
X885401D03*
X846614Y1898113D03*
G54D18*
X85630Y41141D03*
Y46141D03*
Y51141D03*
Y56141D03*
Y61141D03*
Y66141D03*
Y136141D03*
Y141141D03*
Y146141D03*
Y71141D03*
Y76141D03*
Y81141D03*
Y86141D03*
Y91141D03*
Y96141D03*
Y101141D03*
Y106141D03*
Y111141D03*
Y151141D03*
Y156141D03*
Y161141D03*
Y166141D03*
Y446653D03*
Y451653D03*
Y456653D03*
Y461653D03*
Y466653D03*
Y471653D03*
Y476653D03*
Y481653D03*
Y541653D03*
Y546653D03*
Y551653D03*
Y556653D03*
Y561653D03*
Y486653D03*
Y491653D03*
Y496653D03*
Y501653D03*
Y506653D03*
Y511653D03*
Y516653D03*
Y566653D03*
Y571653D03*
Y852165D03*
Y857165D03*
Y862165D03*
Y867165D03*
Y872165D03*
Y877165D03*
Y882165D03*
Y887165D03*
Y892165D03*
Y947165D03*
Y952165D03*
Y957165D03*
Y962165D03*
Y967165D03*
Y972165D03*
Y977165D03*
Y897165D03*
Y902165D03*
Y907165D03*
Y912165D03*
Y917165D03*
Y922165D03*
Y1257677D03*
Y1262677D03*
Y1267677D03*
Y1272677D03*
Y1277677D03*
Y1282677D03*
Y1287677D03*
Y1292677D03*
Y1297677D03*
Y1302677D03*
Y1307677D03*
Y1352677D03*
Y1357677D03*
Y1362677D03*
Y1367677D03*
Y1372677D03*
Y1377677D03*
Y1382677D03*
Y1312677D03*
Y1317677D03*
Y1322677D03*
Y1327677D03*
Y1663189D03*
Y1668189D03*
Y1673189D03*
Y1678189D03*
Y1683189D03*
Y1688189D03*
Y1693189D03*
Y1698189D03*
Y1703189D03*
Y1708189D03*
Y1713189D03*
Y1718189D03*
Y1723189D03*
Y1758189D03*
Y1763189D03*
Y1768189D03*
Y1773189D03*
Y1778189D03*
Y1783189D03*
Y1788189D03*
Y1728189D03*
Y1733189D03*
X150591Y228937D03*
Y223937D03*
Y218937D03*
Y213937D03*
Y208937D03*
Y203937D03*
Y233937D03*
Y313937D03*
Y308937D03*
Y303937D03*
Y298937D03*
Y293937D03*
Y288937D03*
Y283937D03*
Y278937D03*
Y273937D03*
Y268937D03*
Y263937D03*
Y258937D03*
Y328937D03*
Y323937D03*
Y318937D03*
Y639449D03*
Y634449D03*
Y629449D03*
Y624449D03*
Y619449D03*
Y614449D03*
Y609449D03*
Y729449D03*
Y724449D03*
Y719449D03*
Y714449D03*
Y709449D03*
Y704449D03*
Y699449D03*
Y694449D03*
Y689449D03*
Y684449D03*
Y679449D03*
Y674449D03*
Y669449D03*
Y664449D03*
Y734449D03*
Y1044961D03*
Y1039961D03*
Y1034961D03*
Y1029961D03*
Y1024961D03*
Y1019961D03*
Y1014961D03*
Y1139961D03*
Y1134961D03*
Y1129961D03*
Y1124961D03*
Y1119961D03*
Y1114961D03*
Y1109961D03*
Y1104961D03*
Y1099961D03*
Y1094961D03*
Y1089961D03*
Y1084961D03*
Y1079961D03*
Y1074961D03*
Y1069961D03*
Y1450473D03*
Y1445473D03*
Y1440473D03*
Y1435473D03*
Y1430473D03*
Y1425473D03*
Y1420473D03*
Y1545473D03*
Y1540473D03*
Y1535473D03*
Y1530473D03*
Y1525473D03*
Y1520473D03*
Y1515473D03*
Y1510473D03*
Y1505473D03*
Y1500473D03*
Y1495473D03*
Y1490473D03*
Y1485473D03*
Y1480473D03*
Y1475473D03*
Y1855985D03*
Y1850985D03*
Y1845985D03*
Y1840985D03*
Y1835985D03*
Y1830985D03*
Y1825985D03*
Y1885985D03*
Y1880985D03*
Y1950985D03*
Y1945985D03*
Y1940985D03*
Y1935985D03*
Y1930985D03*
Y1925985D03*
Y1920985D03*
Y1915985D03*
Y1910985D03*
Y1905985D03*
Y1900985D03*
Y1895985D03*
Y1890985D03*
X878937Y228937D03*
Y223937D03*
Y218937D03*
Y213937D03*
Y208937D03*
Y203937D03*
Y233937D03*
Y313937D03*
Y308937D03*
Y303937D03*
Y298937D03*
Y293937D03*
Y288937D03*
Y283937D03*
Y278937D03*
Y273937D03*
Y268937D03*
Y263937D03*
Y258937D03*
Y328937D03*
Y323937D03*
Y318937D03*
Y639449D03*
Y634449D03*
Y629449D03*
Y624449D03*
Y619449D03*
Y614449D03*
Y609449D03*
Y729449D03*
Y724449D03*
Y719449D03*
Y714449D03*
Y709449D03*
Y704449D03*
Y699449D03*
Y694449D03*
Y689449D03*
Y684449D03*
Y679449D03*
Y674449D03*
Y669449D03*
Y664449D03*
Y734449D03*
Y1044961D03*
Y1039961D03*
Y1034961D03*
Y1029961D03*
Y1024961D03*
Y1019961D03*
Y1014961D03*
Y1139961D03*
Y1134961D03*
Y1129961D03*
Y1124961D03*
Y1119961D03*
Y1114961D03*
Y1109961D03*
Y1104961D03*
Y1099961D03*
Y1094961D03*
Y1089961D03*
Y1084961D03*
Y1079961D03*
Y1074961D03*
Y1069961D03*
Y1450473D03*
Y1445473D03*
Y1440473D03*
Y1435473D03*
Y1430473D03*
Y1425473D03*
Y1420473D03*
Y1545473D03*
Y1540473D03*
Y1535473D03*
Y1530473D03*
Y1525473D03*
Y1520473D03*
Y1515473D03*
Y1510473D03*
Y1505473D03*
Y1500473D03*
Y1495473D03*
Y1490473D03*
Y1485473D03*
Y1480473D03*
Y1475473D03*
Y1855985D03*
Y1850985D03*
Y1845985D03*
Y1840985D03*
Y1835985D03*
Y1830985D03*
Y1825985D03*
Y1885985D03*
Y1880985D03*
Y1950985D03*
Y1945985D03*
Y1940985D03*
Y1935985D03*
Y1930985D03*
Y1925985D03*
Y1920985D03*
Y1915985D03*
Y1910985D03*
Y1905985D03*
Y1900985D03*
Y1895985D03*
Y1890985D03*
G54D54*
X76038Y1929550D03*
X110960D03*
G54D72*
X220319Y66622D03*
Y64654D03*
Y62685D03*
X201033D03*
Y64654D03*
Y66622D03*
X220319Y82371D03*
Y80402D03*
Y78434D03*
Y76465D03*
Y74497D03*
Y72528D03*
Y70559D03*
Y68591D03*
X201033D03*
Y70559D03*
Y72528D03*
Y74497D03*
Y76465D03*
Y78434D03*
Y80402D03*
Y82371D03*
X918856Y75707D03*
Y77676D03*
Y79644D03*
Y81613D03*
Y83581D03*
Y85550D03*
Y87519D03*
Y89487D03*
Y91456D03*
Y93424D03*
Y95393D03*
X938142D03*
Y93424D03*
Y91456D03*
Y89487D03*
Y87519D03*
Y85550D03*
Y83581D03*
Y81613D03*
Y79644D03*
Y77676D03*
Y75707D03*
G54D81*
X876000Y1703899D03*
X879750D03*
X883500D03*
Y1714499D03*
X879750D03*
X876000D03*
G54D36*
X95000Y1113000D03*
X86000D03*
X176500Y414500D03*
X133000Y1196000D03*
X142000D03*
X185500Y414500D03*
X203500Y812500D03*
X212500D03*
X201000Y1655500D03*
X210000D03*
X326000Y380000D03*
X317000D03*
X319500Y785500D03*
X310500D03*
X319500Y1597000D03*
X310500D03*
X369000Y53000D03*
X360000D03*
X753000Y362500D03*
X756000Y761500D03*
X752900Y1164800D03*
X755500Y1568000D03*
X756000Y1972000D03*
X762000Y362500D03*
X765000Y761500D03*
X761900Y1164800D03*
X764500Y1568000D03*
X765000Y1972000D03*
X877500Y1721500D03*
X883500D03*
G54D45*
X18199Y1956050D03*
X36199Y1918050D03*
X100699Y145050D03*
Y141550D03*
X105199Y129550D03*
Y126050D03*
X100645Y550988D03*
Y547488D03*
X101145Y525988D03*
Y522488D03*
X178399Y524850D03*
X102745Y956489D03*
Y952989D03*
X99745Y931489D03*
Y927989D03*
X119200Y1113500D03*
X129150Y1081100D03*
Y1077600D03*
X104028Y1361952D03*
Y1358452D03*
X100528Y1336952D03*
Y1333452D03*
X103699Y1767550D03*
Y1764050D03*
X101699Y1743050D03*
Y1739550D03*
X179699Y99050D03*
X697749Y1813134D03*
X835699Y167550D03*
X836199Y1788050D03*
X903699Y124550D03*
X951199Y96050D03*
G54D63*
X140749Y474550D03*
X159249D03*
X140999Y508113D03*
X159499D03*
X164249Y873113D03*
Y906613D03*
X105749Y1288613D03*
X124249D03*
X105749Y1255113D03*
X124249D03*
X107249Y1693113D03*
X125749D03*
X106749Y1659613D03*
X125249D03*
X219248Y296614D03*
X237748D03*
X219248Y329614D03*
X237748D03*
X219749Y703050D03*
X238249D03*
X219249Y737050D03*
X237749D03*
X182749Y873113D03*
Y906613D03*
X219250Y1103100D03*
X237750D03*
X218050Y1513400D03*
X236550D03*
X219249Y1546050D03*
X237749D03*
X219684Y1906687D03*
X238184D03*
X218184Y1942987D03*
X236684D03*
X295249Y43613D03*
X313749D03*
X295249Y77113D03*
X313749D03*
X837978Y290124D03*
X841478Y323924D03*
X836196Y691182D03*
X839249Y724550D03*
X836333Y1096692D03*
X839749Y1129550D03*
X838077Y1501596D03*
X838314Y1907313D03*
X841249Y1940550D03*
X856478Y290124D03*
X859978Y323924D03*
X854696Y691182D03*
X857749Y724550D03*
X854833Y1096692D03*
X858249Y1129550D03*
X856577Y1501596D03*
X861077Y1534296D03*
X842577D03*
X856814Y1907313D03*
X859749Y1940550D03*
G54D37*
X88300Y1097500D03*
Y1104500D03*
X57299Y1901550D03*
X39799Y1921550D03*
X131799Y224550D03*
Y228050D03*
Y249050D03*
Y252550D03*
X135238Y630065D03*
Y633565D03*
Y654565D03*
Y658065D03*
X132799Y1035550D03*
Y1039050D03*
Y1060050D03*
Y1063550D03*
X143300Y1206000D03*
X109250Y1348100D03*
Y1344600D03*
X131190Y1441241D03*
Y1444741D03*
Y1465741D03*
Y1469241D03*
X131892Y1846254D03*
Y1849754D03*
Y1870754D03*
Y1874254D03*
X859278Y224924D03*
Y228424D03*
Y249424D03*
Y252924D03*
X859496Y630382D03*
Y633882D03*
Y654882D03*
Y658382D03*
X859133Y1035892D03*
Y1039392D03*
Y1060892D03*
Y1064392D03*
X860627Y1440796D03*
Y1444296D03*
Y1465796D03*
Y1469296D03*
X862614Y1846613D03*
Y1850113D03*
Y1871113D03*
Y1874613D03*
G54D73*
X238249Y102050D03*
G54D19*
X20700Y119500D03*
Y114500D03*
X180199Y95050D03*
X900699Y115050D03*
X890600Y1716200D03*
X878601Y1693850D03*
X965400Y1665500D03*
Y1660500D03*
G54D82*
X854101Y1710351D03*
Y1733149D03*
G54D64*
X145439Y426863D03*
X147999D03*
X150559D03*
Y433363D03*
X145439D03*
X167439Y820363D03*
X169999D03*
X172559D03*
Y826863D03*
X167439D03*
X109439Y1079300D03*
X111999D03*
X114559D03*
Y1085800D03*
X109439D03*
X106939Y1210363D03*
X109499D03*
X112059D03*
Y1216863D03*
X106939D03*
X114939Y1305300D03*
X120059D03*
Y1311800D03*
X117499D03*
X114939D03*
X132939Y1714800D03*
X135499D03*
X138059D03*
Y1721300D03*
X132939D03*
X208559Y891800D03*
X205999D03*
X203439D03*
Y885300D03*
X208559D03*
X284059Y333800D03*
X281499D03*
X278939D03*
Y327300D03*
X284059D03*
X285059Y740300D03*
X282499D03*
X279939D03*
Y733800D03*
X285059D03*
X284059Y1551300D03*
X281499D03*
X278939D03*
Y1544800D03*
X284059D03*
X288709Y1942700D03*
X286149D03*
X283589D03*
Y1936200D03*
X288709D03*
X790559Y327800D03*
X787999D03*
X785439D03*
Y321300D03*
X790559D03*
X790059Y728800D03*
X787499D03*
X784939D03*
Y722300D03*
X790059D03*
X789559Y1131800D03*
X786999D03*
X784439D03*
Y1125300D03*
X789559D03*
X792813Y1535628D03*
X790253D03*
X787693D03*
Y1529128D03*
X792813D03*
X791059Y1942300D03*
X788499D03*
X785939D03*
Y1935800D03*
X791059D03*
G54D28*
X42449Y211775D03*
Y204025D03*
X49949Y207900D03*
X74049Y648025D03*
Y655775D03*
X66549Y651900D03*
X20849Y1059925D03*
Y1052175D03*
X28349Y1056050D03*
X60449Y1846475D03*
Y1838725D03*
X67949Y1842600D03*
X137249Y1347675D03*
Y1355425D03*
X129749Y1351550D03*
X193549Y157325D03*
Y165075D03*
X186049Y161200D03*
X193549Y564525D03*
Y572275D03*
X186049Y568400D03*
X193549Y968225D03*
Y975975D03*
X186049Y972100D03*
X208049Y1372925D03*
Y1380675D03*
X200549Y1376800D03*
X194049Y1778625D03*
Y1786375D03*
X186549Y1782500D03*
X922049Y563025D03*
Y570775D03*
X914549Y566900D03*
X922049Y967225D03*
Y974975D03*
X914549Y971100D03*
X856449Y1366675D03*
Y1358925D03*
X863949Y1362800D03*
X921549Y1777125D03*
Y1784875D03*
X914049Y1781000D03*
X939549Y163825D03*
Y171575D03*
X932049Y167700D03*
G54D46*
X21799Y1956050D03*
X39799Y1918050D03*
X104299Y145050D03*
Y141550D03*
X108799Y129550D03*
Y126050D03*
X104245Y550988D03*
Y547488D03*
X104745Y525988D03*
Y522488D03*
X106345Y956489D03*
Y952989D03*
X103345Y931489D03*
Y927989D03*
X122800Y1113500D03*
X132750Y1081100D03*
Y1077600D03*
X107628Y1361952D03*
Y1358452D03*
X104128Y1336952D03*
Y1333452D03*
X107299Y1767550D03*
Y1764050D03*
X105299Y1743050D03*
Y1739550D03*
X183299Y99050D03*
X181999Y524850D03*
X701349Y1813134D03*
X839299Y167550D03*
X839799Y1788050D03*
X907299Y124550D03*
X954799Y96050D03*
G54D55*
X50299Y1946650D03*
X53999D03*
X42532Y1946783D03*
X44399Y1942250D03*
X38703Y1946754D03*
X34799Y1946750D03*
X46565Y1946703D03*
X44368Y1951450D03*
X210638Y62959D03*
X210634Y66863D03*
X215138Y72559D03*
X210685Y74725D03*
X210605Y70692D03*
X205938Y72528D03*
X210738Y78459D03*
Y82159D03*
X923761Y85550D03*
X932961Y85581D03*
X928461Y75981D03*
X928561Y91481D03*
X928508Y87747D03*
X928428Y83714D03*
X928561Y95181D03*
X928457Y79885D03*
G54D47*
X49999Y1971850D03*
X143499Y523413D03*
X166499Y921913D03*
X136600Y1180200D03*
X107999Y1303913D03*
X109499Y1708413D03*
X218998Y317914D03*
X213598Y350914D03*
X218499Y724850D03*
X214599Y757850D03*
X217600Y1127800D03*
X217999Y1534850D03*
X218814Y1925913D03*
X213600Y1962400D03*
X297499Y92413D03*
X783049Y1819434D03*
X788049D03*
X858999Y311850D03*
X864900Y344900D03*
X855696Y712182D03*
X862896Y746382D03*
X855333Y1117692D03*
X862933Y1149192D03*
X857827Y1522596D03*
X865700Y1552400D03*
X857314Y1928413D03*
X864500Y1962200D03*
G54D38*
X84700Y1097500D03*
Y1104500D03*
X53699Y1901550D03*
X36199Y1921550D03*
X128199Y224550D03*
Y228050D03*
Y249050D03*
Y252550D03*
X131638Y630065D03*
Y633565D03*
Y654565D03*
Y658065D03*
X129199Y1035550D03*
Y1039050D03*
Y1060050D03*
Y1063550D03*
X139700Y1206000D03*
X105650Y1348100D03*
Y1344600D03*
X127590Y1441241D03*
Y1444741D03*
Y1465741D03*
Y1469241D03*
X128292Y1846254D03*
Y1849754D03*
Y1870754D03*
Y1874254D03*
X855678Y224924D03*
Y228424D03*
Y249424D03*
Y252924D03*
X855896Y630382D03*
Y633882D03*
Y654882D03*
Y658382D03*
X855533Y1035892D03*
Y1039392D03*
Y1060892D03*
Y1064392D03*
X857027Y1440796D03*
Y1444296D03*
Y1465796D03*
Y1469296D03*
X859014Y1846613D03*
Y1850113D03*
Y1871113D03*
Y1874613D03*
G54D65*
X140940Y550300D03*
X143500D03*
X146060D03*
Y557700D03*
X143500D03*
X140940D03*
X172240Y1678400D03*
X174800D03*
X177360D03*
Y1685800D03*
X174800D03*
X172240D03*
X242040Y275100D03*
X244600D03*
X247160D03*
Y282500D03*
X244600D03*
X242040D03*
X241440Y682500D03*
X244000D03*
X246560D03*
Y689900D03*
X244000D03*
X241440D03*
X181340Y937100D03*
X183900D03*
X186460D03*
Y944500D03*
X183900D03*
X181340D03*
X315939Y352350D03*
X318499D03*
X321059D03*
Y359750D03*
X318499D03*
X315939D03*
X316939Y759350D03*
X319499D03*
X322059D03*
Y766750D03*
X319499D03*
X316939D03*
X315939Y1569850D03*
X318499D03*
X321059D03*
Y1577250D03*
X318499D03*
X315939D03*
X319080Y1959072D03*
X321640D03*
X324200D03*
Y1966472D03*
X321640D03*
X319080D03*
G54D56*
X20087Y1973700D03*
X946999Y116300D03*
G54D74*
X240749Y102050D03*
G54D29*
X69510Y217221D03*
X61757Y216415D03*
X52499Y198550D03*
X56999Y217050D03*
X77749Y213500D03*
X41499Y219050D03*
X52730Y406470D03*
X60400Y616000D03*
X62500Y633300D03*
X34700Y623000D03*
X41367Y639102D03*
X53400Y630500D03*
X66023Y638100D03*
X71800Y622700D03*
X76499Y637550D03*
X43500Y631500D03*
X55500Y618500D03*
X39499Y615550D03*
X28586Y600248D03*
X28519Y605048D03*
X61999Y661550D03*
X40734Y802473D03*
X52499Y1013550D03*
X74999Y1126550D03*
X26500Y1064500D03*
X96000Y1107000D03*
X95899Y1475350D03*
X38499Y1601050D03*
X42449Y1588600D03*
X63014Y1560986D03*
X60172Y1566828D03*
X78099Y1827250D03*
X89499Y1843113D03*
X83499Y1841550D03*
X81499Y1847550D03*
X77999Y1832350D03*
X46499Y1850050D03*
X46999Y1832550D03*
X57999Y1830050D03*
X90800Y1832500D03*
X36699Y1963300D03*
X28389Y1958362D03*
X26499Y1947050D03*
X33573Y1928650D03*
X41597Y1912934D03*
X43999Y1924050D03*
X39990Y1927445D03*
X44624Y1974886D03*
X26999Y1973550D03*
X166999Y155550D03*
X171499Y153550D03*
X162177Y154550D03*
X137500Y444600D03*
X132999Y475550D03*
X144999Y419550D03*
X168500Y472000D03*
X161999Y426450D03*
X175000Y425000D03*
X156959Y426292D03*
X162000Y421250D03*
X171000Y414500D03*
X167200Y561000D03*
X151699Y524650D03*
X135300Y524329D03*
X168299Y503150D03*
X172199Y557108D03*
X157749Y562000D03*
X155999Y535775D03*
X156499Y548550D03*
X177999Y559300D03*
X134899Y538200D03*
X135300Y549500D03*
X166499Y841550D03*
X106499Y834550D03*
X156969Y917050D03*
X171499Y965050D03*
X158800Y967500D03*
X164999Y965050D03*
X160999Y942550D03*
X171000Y927000D03*
X125999Y1087550D03*
X126999Y1143550D03*
X124249Y1108500D03*
X121245Y1120753D03*
X131491Y1128483D03*
X113500Y1134500D03*
X127800Y1163400D03*
X100499Y1226050D03*
X99999Y1202550D03*
X173499Y1217050D03*
X158500Y1181000D03*
X115499Y1197550D03*
X117499Y1214050D03*
X121000Y1207000D03*
X148500Y1196000D03*
X100999Y1213550D03*
X127500Y1207500D03*
X127000Y1196000D03*
X143900Y1262600D03*
X146300Y1277900D03*
X164999Y1305550D03*
X113999Y1380550D03*
X115499Y1364550D03*
X105999Y1311050D03*
X148000Y1346500D03*
X116499Y1335050D03*
X176999Y1367550D03*
X123500Y1372000D03*
X171499Y1370550D03*
X112499Y1329050D03*
X136200Y1342600D03*
X153500Y1326700D03*
X129699Y1315605D03*
X120499Y1470550D03*
X97999Y1486550D03*
X121499Y1511050D03*
X108000Y1517000D03*
X135400Y1624100D03*
X171999Y1658550D03*
X121499Y1708050D03*
X168999Y1651050D03*
X143500Y1702900D03*
X151499Y1673550D03*
X144999Y1711050D03*
X174800Y1670800D03*
X148100Y1683400D03*
X172999Y1775050D03*
X109249Y1725800D03*
X177314Y1772050D03*
X158027Y1778300D03*
X166999Y1774550D03*
X158499Y1729050D03*
X208999Y92050D03*
X227022Y85278D03*
X229296Y81050D03*
X230811Y88226D03*
X224499Y92050D03*
X225499Y100050D03*
X188999Y88550D03*
X187024Y76235D03*
X191499Y74497D03*
X200999Y159050D03*
X201561Y164541D03*
X218499Y183050D03*
X191449Y152000D03*
X221799Y276150D03*
X212578Y287448D03*
X212499Y296050D03*
X257000Y316214D03*
X212499Y307050D03*
X231400Y262800D03*
X236800Y283500D03*
X211999Y327550D03*
X253999Y370050D03*
X207128Y440421D03*
X179000Y535500D03*
X179499Y542550D03*
X215400Y516400D03*
X199800Y546100D03*
X193999Y558050D03*
X200999Y565050D03*
X200417Y569815D03*
X258200Y722300D03*
X216999Y713050D03*
X213299Y693800D03*
X212499Y701550D03*
X239300Y669600D03*
X234500Y690652D03*
X212499Y736050D03*
X247000Y768500D03*
X244700Y743100D03*
X217500Y812500D03*
X232500Y834500D03*
X179999Y826050D03*
X179499Y820550D03*
X191936Y825184D03*
X199500Y819132D03*
X199999Y971050D03*
X203000Y918000D03*
X237499Y900050D03*
X178999Y961550D03*
X227500Y943500D03*
X193549Y962550D03*
X194800Y925500D03*
X188499Y982050D03*
X250000Y1128000D03*
X233500Y1113100D03*
X244400Y1110200D03*
X255999Y1112150D03*
X212600Y1089961D03*
X210999Y1100550D03*
X227028Y1071148D03*
X223700Y1078500D03*
X250800Y1166700D03*
X186000Y1382400D03*
X216499Y1377550D03*
X190499Y1367550D03*
X197999Y1359050D03*
X208999Y1366550D03*
X259000Y1534000D03*
X217500Y1522500D03*
X260500Y1541000D03*
X212000Y1544500D03*
X211914Y1504015D03*
X211500Y1512000D03*
X223501Y1487433D03*
X242700Y1499400D03*
X253500Y1586500D03*
X195000Y1640613D03*
X184000Y1695000D03*
X197500Y1650000D03*
X192800Y1658800D03*
X201499Y1784750D03*
X192999Y1771550D03*
X240100Y1875000D03*
X218499Y1897050D03*
X245249Y1896283D03*
X286499Y43613D03*
X305999Y141050D03*
X287100Y86363D03*
X328500Y71500D03*
X307300Y113300D03*
X295500Y101900D03*
X299000Y340500D03*
X265499Y322050D03*
X312912Y345936D03*
X302000Y373000D03*
X319102Y346300D03*
X324644Y367083D03*
X320500Y373000D03*
X283999Y708550D03*
X301099Y750750D03*
X330249Y750050D03*
X318499Y752050D03*
X304000Y785500D03*
X324499Y753050D03*
X323500Y772300D03*
X325000Y785500D03*
X301499Y927050D03*
X304499Y1549550D03*
X343699Y1475950D03*
X317499Y1549050D03*
X279500Y1521000D03*
X328600Y1566100D03*
X304000Y1597000D03*
X323000Y1582600D03*
X324500Y1597000D03*
X268499Y1706550D03*
X297499Y1797050D03*
X278999Y1950550D03*
X306199Y1937010D03*
X335520Y1953650D03*
X319500Y1954500D03*
X329500Y1956500D03*
X323999Y1938550D03*
X325500Y1971500D03*
X330000Y1962500D03*
X305691Y1976200D03*
X409999Y54050D03*
X404499Y39300D03*
X359000Y47500D03*
X361616Y58933D03*
X402999Y46550D03*
X381500Y46000D03*
X377500Y49000D03*
X411300Y328000D03*
X503379Y621150D03*
X478599Y1075450D03*
X496300Y1492000D03*
X509900Y1731700D03*
X459999Y1862050D03*
X530200Y1327300D03*
X646100Y106900D03*
X599499Y79550D03*
X640300Y911500D03*
X659949Y1803670D03*
X664549Y1797436D03*
X634999Y1803050D03*
X633931Y1795465D03*
X661549Y1822634D03*
X746999Y325550D03*
X752999Y343550D03*
X748000Y333000D03*
X745696Y725050D03*
X746999Y741050D03*
X747500Y733762D03*
X745599Y1129050D03*
X747000Y1142550D03*
X754151Y1135982D03*
X690999Y1295550D03*
X745600Y1531296D03*
X750000Y1546000D03*
X752099Y1539972D03*
X732549Y1802934D03*
X738049Y1793884D03*
X685549Y1799134D03*
X715549Y1799634D03*
X717564Y1804045D03*
X741549Y1818384D03*
X681549Y1825234D03*
X687049Y1822334D03*
X720300Y1808884D03*
X749499Y1933050D03*
X744000Y1965000D03*
X746000Y1953500D03*
X746149Y1945000D03*
X840499Y182550D03*
X817999Y182050D03*
X818013Y173064D03*
X827774Y213183D03*
X836499Y213162D03*
X838299Y204800D03*
X829999Y200550D03*
X830000Y294500D03*
X785999Y285550D03*
X836600Y261000D03*
X806499Y364152D03*
X769000Y347500D03*
X774000Y333500D03*
X761500Y348500D03*
X815000Y687500D03*
X776999Y690050D03*
X835300Y663200D03*
X779500Y736000D03*
X774500Y733000D03*
X761500Y747500D03*
X827000Y1102000D03*
X781999Y1085050D03*
X834500Y1067600D03*
X770000Y1137900D03*
Y1151000D03*
X761998Y1151400D03*
X836600Y1471100D03*
X822100Y1470700D03*
X829500Y1506000D03*
X791499Y1492550D03*
X770500Y1554000D03*
X774214Y1541656D03*
X763000Y1555000D03*
X768300Y1778000D03*
X829199Y1783750D03*
X819593Y1783807D03*
X817249Y1793050D03*
X785799Y1795634D03*
X768549Y1816634D03*
X840400Y1827100D03*
X786699Y1808934D03*
X823499Y1825050D03*
X815499Y1817050D03*
X822700Y1875100D03*
X837499Y1876900D03*
X809600Y1887560D03*
X790499Y1899550D03*
X770000Y1956500D03*
X829000Y1913000D03*
X773250Y1944000D03*
X776000Y1949000D03*
X780000Y1976000D03*
X910499Y98550D03*
X905499Y94550D03*
X912399Y88150D03*
X916999Y168424D03*
X907499Y160434D03*
X882999D03*
X885499Y165050D03*
X922999Y158550D03*
X854200Y269500D03*
X847577Y272131D03*
X847200Y267200D03*
X873999Y484550D03*
X899685Y559592D03*
X886749Y560500D03*
X894200Y560400D03*
X906999Y557050D03*
X921999D03*
X876787Y567743D03*
X855499Y700550D03*
X847200Y672000D03*
X860499Y691050D03*
X852703Y667497D03*
X846400Y665500D03*
X862700Y735300D03*
X905999Y962050D03*
X886583Y967600D03*
X877499Y977050D03*
X894999Y963050D03*
X922049Y961050D03*
X855500Y1106500D03*
X863000Y1139000D03*
X851600Y1073300D03*
X846400Y1078700D03*
X862000Y1094500D03*
X846500Y1073500D03*
X880499Y1367550D03*
X869587Y1354050D03*
X882999Y1374550D03*
X879999Y1380170D03*
X891999Y1363550D03*
X847500Y1367000D03*
X858500Y1511000D03*
X854327Y1481596D03*
X848300Y1483000D03*
X845700Y1477100D03*
X893500Y1694500D03*
X871100Y1690300D03*
X901500Y1716000D03*
X886200Y1776200D03*
X897239Y1771500D03*
X914999Y1791500D03*
X892999Y1776050D03*
X899599Y1776604D03*
X921499Y1770050D03*
X849800Y1888300D03*
X846000Y1811400D03*
X854814Y1887250D03*
X847700Y1881900D03*
X964042Y96050D03*
X954499Y116550D03*
X944499Y95050D03*
X941873Y103050D03*
X935999Y104050D03*
X926499Y103050D03*
X945999Y166550D03*
X937499Y158500D03*
X927999Y568550D03*
X929499Y971100D03*
G54D83*
X1005807Y1636102D03*
Y1631102D03*
Y1626102D03*
Y1621102D03*
Y1676102D03*
Y1671102D03*
Y1666102D03*
Y1661102D03*
Y1656102D03*
Y1651102D03*
Y1646102D03*
Y1641102D03*
G54D57*
X20087Y1976200D03*
X946999Y118800D03*
G54D75*
X231500Y269350D03*
X235375Y276850D03*
X227625D03*
X230900Y676250D03*
X234775Y683750D03*
X227025D03*
X232700Y1485950D03*
X236575Y1493450D03*
X228825D03*
X240100Y1880450D03*
X243975Y1887950D03*
X236225D03*
X836700Y267450D03*
X840575Y274950D03*
X832825D03*
X835300Y670150D03*
X839175Y677650D03*
X831425D03*
X835000Y1075750D03*
X838875Y1083250D03*
X831125D03*
X836900Y1479050D03*
X840775Y1486550D03*
X833025D03*
X837499Y1884800D03*
X833624Y1892300D03*
X841374D03*
G54D84*
X1019291Y1416024D03*
Y1694212D03*
G54D66*
X176999Y490913D03*
Y488353D03*
Y485793D03*
X116249Y1093990D03*
Y1096550D03*
Y1099110D03*
X109749D03*
Y1093990D03*
X117249Y1720110D03*
Y1717550D03*
Y1714990D03*
X123749D03*
Y1720110D03*
X183499Y485793D03*
Y490913D03*
X321748Y334054D03*
Y336614D03*
Y339174D03*
X315248D03*
Y334054D03*
X323249Y740990D03*
Y743550D03*
Y746110D03*
X316749D03*
Y740990D03*
X319749Y1554490D03*
Y1557050D03*
X313249Y1554490D03*
X319749Y1559610D03*
X313249D03*
X326971Y1944349D03*
Y1946909D03*
Y1949469D03*
X320471D03*
Y1944349D03*
X347749Y67110D03*
Y64550D03*
Y61990D03*
X354249D03*
Y67110D03*
X387749Y56110D03*
Y53550D03*
Y50990D03*
X394249D03*
Y56110D03*
X767728Y323864D03*
Y326424D03*
Y328984D03*
X761228D03*
Y323864D03*
X766946Y724822D03*
Y727382D03*
X760446Y724822D03*
X766946Y729942D03*
X760446D03*
X767083Y1126332D03*
Y1128892D03*
Y1131452D03*
X760583D03*
Y1126332D03*
X770077Y1531236D03*
Y1533796D03*
Y1536356D03*
X763577D03*
Y1531236D03*
X766564Y1937153D03*
Y1939713D03*
Y1942273D03*
X760064D03*
Y1937153D03*
G54D39*
X20300Y1097500D03*
Y1102500D03*
X242299Y76550D03*
X895300Y1721500D03*
X958299Y89550D03*
G54D48*
X49999Y1966250D03*
X143499Y517813D03*
X166499Y916313D03*
X136600Y1174600D03*
X107999Y1298313D03*
X109499Y1702813D03*
X218998Y312314D03*
X213598Y345314D03*
X218499Y719250D03*
X214599Y752250D03*
X217600Y1122200D03*
X217999Y1529250D03*
X218814Y1920313D03*
X213600Y1956800D03*
X297499Y86813D03*
X783049Y1813834D03*
X788049D03*
X858999Y306250D03*
X864900Y339300D03*
X855696Y706582D03*
X862896Y740782D03*
X855333Y1112092D03*
X862933Y1143592D03*
X857827Y1516996D03*
X865700Y1546800D03*
X857314Y1922813D03*
X864500Y1956600D03*
G54D85*
G01X-71137Y-139897D02*
Y-219897D01*
G01D02*
X1129963D01*
G01X-75137Y-123897D02*
G02I-12000J0D01*
G01X-80287D02*
G02I-6850J0D01*
G01X-87137Y-139897D02*
Y-107897D01*
G01X-71137Y-123897D02*
X-103137D01*
G01X-71137Y-139897D02*
X1129963D01*
G01X-71137Y-175397D02*
X1129963D01*
G01X342463Y-139897D02*
Y-219897D01*
G01X479963Y-139897D02*
Y-219897D01*
G01X594963Y-139897D02*
Y-219897D01*
G01X762463Y-139897D02*
Y-219897D01*
G01X932463Y-139897D02*
Y-219897D01*
G01X1129963Y-139897D02*
Y-219897D01*
G01X1157963Y-123897D02*
G02I-12000J0D01*
G01X1152813D02*
G02I-6850J0D01*
G01X1145963Y-139897D02*
Y-107897D01*
G01X1161963Y-123897D02*
X1129963D01*
G54D76*
X241500Y1085625D03*
X234000Y1089500D03*
Y1081750D03*
G54D58*
X143999Y54089D03*
Y89011D03*
X862999Y60089D03*
Y95011D03*
G54D67*
X171557Y533288D03*
X168997D03*
X166437D03*
X163877D03*
Y549468D03*
X166437D03*
X168997D03*
X171557D03*
X116045Y1484981D03*
X113485D03*
X110925D03*
X108365D03*
Y1501161D03*
X110925D03*
X113485D03*
X116045D03*
X833013Y176949D03*
X830453D03*
X827893D03*
X825333D03*
Y193129D03*
X827893D03*
X830453D03*
X833013D03*
Y1798997D03*
X830453D03*
X827893D03*
X825333D03*
Y1815177D03*
X827893D03*
X830453D03*
X833013D03*
G54D49*
X18499Y1923750D03*
X134300Y455000D03*
X139499Y488813D03*
X162499Y886313D03*
X162999Y852813D03*
X104499Y1267813D03*
X103999Y1235250D03*
X102100Y1638700D03*
X105499Y1673313D03*
X221498Y281314D03*
X221499Y687750D03*
X217500Y1084200D03*
X253200Y1534900D03*
X220999Y1497750D03*
X227814Y1891313D03*
X293999Y56313D03*
X289099Y23313D03*
X853978Y275124D03*
X852696Y676082D03*
X852333Y1081592D03*
X854327Y1486496D03*
X894800Y1704200D03*
X854814Y1892313D03*
G54D86*
G01X-89222Y-207897D02*
Y-190397D01*
G01X-80052D02*
Y-207897D01*
G01Y-199147D02*
X-89222D01*
G01X-67137Y-207897D02*
X-68447Y-207605D01*
X-69757Y-206439D01*
X-70631Y-204397D01*
X-71067Y-202064D01*
X-70631Y-199730D01*
X-69757Y-197689D01*
X-68447Y-196522D01*
X-67137Y-196231D01*
X-65827Y-196522D01*
X-64517Y-197689D01*
X-63644Y-199730D01*
X-63425Y-202064D01*
X-63644Y-204397D01*
X-64517Y-206439D01*
X-65827Y-207605D01*
X-67137Y-207897D01*
G01X-53349D02*
Y-196231D01*
G01Y-199147D02*
X-52475Y-197689D01*
X-51165Y-196522D01*
X-49419Y-196231D01*
X-47891Y-196522D01*
X-46580Y-197689D01*
X-45925Y-199730D01*
Y-207897D01*
G01X-35412Y-200022D02*
X-28425D01*
X-29080Y-197980D01*
X-30172Y-196814D01*
X-31700Y-196231D01*
X-33229Y-196522D01*
X-34539Y-197397D01*
X-35412Y-199439D01*
X-35849Y-201189D01*
Y-202939D01*
X-35412Y-204689D01*
X-34320Y-206439D01*
X-33010Y-207605D01*
X-31482Y-207897D01*
X-29954Y-207314D01*
X-28425Y-205564D01*
G01X-19222Y-213147D02*
X-17912Y-213730D01*
X-16165Y-213147D01*
X-15074Y-211981D01*
X-14200Y-210522D01*
X-12891Y-205856D01*
X-10052Y-196231D01*
G01X-17039D02*
X-12891Y-205856D01*
G01X22109Y-198564D02*
X22983Y-197689D01*
X23638Y-196231D01*
X24075Y-194188D01*
X23638Y-192439D01*
X22765Y-191272D01*
X21236Y-190397D01*
X15341D01*
Y-207897D01*
X22546D01*
X24075Y-206731D01*
X24948Y-204980D01*
X25385Y-202939D01*
X24948Y-200897D01*
X23638Y-199147D01*
X22109Y-198564D01*
X15341D01*
G01X41793Y-207897D02*
Y-196231D01*
G01Y-198272D02*
X40920Y-197106D01*
X39609Y-196522D01*
X38081Y-196231D01*
X36553Y-196814D01*
X35243Y-197980D01*
X34369Y-199730D01*
X33933Y-202064D01*
X34369Y-204397D01*
X35243Y-206147D01*
X36553Y-207314D01*
X38081Y-207897D01*
X39609Y-207605D01*
X40920Y-206731D01*
X41793Y-205564D01*
G01X59293Y-190397D02*
Y-207897D01*
G01Y-205273D02*
X58420Y-206731D01*
X57109Y-207605D01*
X55581Y-207897D01*
X53835Y-207314D01*
X52525Y-205856D01*
X51651Y-204106D01*
X51433Y-202064D01*
X51651Y-200022D01*
X52525Y-198272D01*
X53835Y-196814D01*
X55581Y-196231D01*
X57109Y-196522D01*
X58201Y-197106D01*
X59293Y-198272D01*
G01X69806Y-212272D02*
X71335Y-213439D01*
X73081Y-213730D01*
X74609Y-213439D01*
X75920Y-211981D01*
X76793Y-209939D01*
Y-196231D01*
G01Y-198564D02*
X75920Y-197397D01*
X74609Y-196522D01*
X73081Y-196231D01*
X71335Y-196814D01*
X70243Y-197980D01*
X69369Y-200022D01*
X68933Y-202064D01*
X69151Y-203814D01*
X70025Y-205856D01*
X71335Y-207314D01*
X73081Y-207897D01*
X74391Y-207605D01*
X75920Y-206439D01*
X76793Y-205273D01*
G01X87088Y-200022D02*
X94075D01*
X93420Y-197980D01*
X92328Y-196814D01*
X90800Y-196231D01*
X89271Y-196522D01*
X87961Y-197397D01*
X87088Y-199439D01*
X86651Y-201189D01*
Y-202939D01*
X87088Y-204689D01*
X88180Y-206439D01*
X89490Y-207605D01*
X91018Y-207897D01*
X92546Y-207314D01*
X94075Y-205564D01*
G01X104806Y-207897D02*
Y-196231D01*
G01Y-198564D02*
X105898Y-197397D01*
X106990Y-196522D01*
X108518Y-196231D01*
X109609Y-196522D01*
X110920Y-197397D01*
G01X138060Y-207897D02*
Y-190397D01*
X142426D01*
X144173Y-191272D01*
X145483Y-192439D01*
X146575Y-194188D01*
X147448Y-196231D01*
X147666Y-199147D01*
X147448Y-202064D01*
X146575Y-204106D01*
X145483Y-205856D01*
X144173Y-207022D01*
X142426Y-207897D01*
X138060D01*
G01X155996D02*
Y-190397D01*
X161236D01*
X162983Y-191272D01*
X164293Y-193314D01*
X164730Y-195647D01*
X164293Y-197980D01*
X163201Y-199730D01*
X161236Y-200606D01*
X155996D01*
G01X179609Y-198564D02*
X180483Y-197689D01*
X181138Y-196231D01*
X181575Y-194188D01*
X181138Y-192439D01*
X180265Y-191272D01*
X178736Y-190397D01*
X172841D01*
Y-207897D01*
X180046D01*
X181575Y-206731D01*
X182448Y-204980D01*
X182885Y-202939D01*
X182448Y-200897D01*
X181138Y-199147D01*
X179609Y-198564D01*
X172841D01*
G01X208496Y-190397D02*
Y-207897D01*
X217230D01*
G01X230363D02*
X229053Y-207605D01*
X227743Y-206439D01*
X226869Y-204397D01*
X226433Y-202064D01*
X226869Y-199730D01*
X227743Y-197689D01*
X229053Y-196522D01*
X230363Y-196231D01*
X231673Y-196522D01*
X232983Y-197689D01*
X233856Y-199730D01*
X234075Y-202064D01*
X233856Y-204397D01*
X232983Y-206439D01*
X231673Y-207605D01*
X230363Y-207897D01*
G01X242404Y-196231D02*
X245025Y-207897D01*
X247863Y-196231D01*
X250701Y-207897D01*
X253322Y-196231D01*
G01X278496Y-190397D02*
Y-207897D01*
X287230D01*
G01X300363D02*
X299053Y-207605D01*
X297743Y-206439D01*
X296869Y-204397D01*
X296433Y-202064D01*
X296869Y-199730D01*
X297743Y-197689D01*
X299053Y-196522D01*
X300363Y-196231D01*
X301673Y-196522D01*
X302983Y-197689D01*
X303856Y-199730D01*
X304075Y-202064D01*
X303856Y-204397D01*
X302983Y-206439D01*
X301673Y-207605D01*
X300363Y-207897D01*
G01X314588Y-205856D02*
X315680Y-207022D01*
X317208Y-207897D01*
X318518D01*
X319828Y-207314D01*
X320701Y-206439D01*
X321138Y-205273D01*
X320920Y-203522D01*
X320046Y-202647D01*
X316116Y-200897D01*
X315243Y-198855D01*
X315680Y-197397D01*
X316553Y-196522D01*
X317863Y-196231D01*
X319173Y-196522D01*
X320483Y-197397D01*
G01X332088Y-205856D02*
X333180Y-207022D01*
X334708Y-207897D01*
X336018D01*
X337328Y-207314D01*
X338201Y-206439D01*
X338638Y-205273D01*
X338420Y-203522D01*
X337546Y-202647D01*
X333616Y-200897D01*
X332743Y-198855D01*
X333180Y-197397D01*
X334053Y-196522D01*
X335363Y-196231D01*
X336673Y-196522D01*
X337983Y-197397D01*
G01X94686Y-164897D02*
Y-147397D01*
X100363Y-161980D01*
X106040Y-147397D01*
Y-164897D01*
G01X117863D02*
X116553Y-164605D01*
X115243Y-163439D01*
X114369Y-161397D01*
X113933Y-159064D01*
X114369Y-156730D01*
X115243Y-154689D01*
X116553Y-153522D01*
X117863Y-153231D01*
X119173Y-153522D01*
X120483Y-154689D01*
X121356Y-156730D01*
X121575Y-159064D01*
X121356Y-161397D01*
X120483Y-163439D01*
X119173Y-164605D01*
X117863Y-164897D01*
G01X139293Y-147397D02*
Y-164897D01*
G01Y-162273D02*
X138420Y-163731D01*
X137109Y-164605D01*
X135581Y-164897D01*
X133835Y-164314D01*
X132525Y-162856D01*
X131651Y-161106D01*
X131433Y-159064D01*
X131651Y-157022D01*
X132525Y-155272D01*
X133835Y-153814D01*
X135581Y-153231D01*
X137109Y-153522D01*
X138201Y-154106D01*
X139293Y-155272D01*
G01X149588Y-157022D02*
X156575D01*
X155920Y-154980D01*
X154828Y-153814D01*
X153300Y-153231D01*
X151771Y-153522D01*
X150461Y-154397D01*
X149588Y-156439D01*
X149151Y-158189D01*
Y-159939D01*
X149588Y-161689D01*
X150680Y-163439D01*
X151990Y-164605D01*
X153518Y-164897D01*
X155046Y-164314D01*
X156575Y-162564D01*
G01X170363Y-164897D02*
Y-147397D01*
G01X376163Y-209897D02*
Y-192397D01*
X373543Y-195897D01*
G01Y-209897D02*
X378783D01*
G01X396283D02*
Y-192397D01*
X388204Y-204939D01*
X399122D01*
G01X406360Y-207273D02*
X407669Y-208731D01*
X409198Y-209605D01*
X411163Y-209897D01*
X413128Y-209314D01*
X414656Y-208147D01*
X415748Y-206106D01*
X415966Y-203772D01*
X415530Y-201439D01*
X414438Y-199980D01*
X412909Y-198814D01*
X411381Y-198522D01*
X409853Y-198814D01*
X407888Y-199980D01*
X408543Y-192397D01*
X414438D01*
G01X431283Y-209897D02*
Y-192397D01*
X423204Y-204939D01*
X434122D01*
G01X441360Y-207273D02*
X442669Y-208731D01*
X444198Y-209605D01*
X446163Y-209897D01*
X448128Y-209314D01*
X449656Y-208147D01*
X450748Y-206106D01*
X450966Y-203772D01*
X450530Y-201439D01*
X449438Y-199980D01*
X447909Y-198814D01*
X446381Y-198522D01*
X444853Y-198814D01*
X442888Y-199980D01*
X443543Y-192397D01*
X449438D01*
G01X363046Y-164897D02*
Y-147397D01*
X368286D01*
X370033Y-148272D01*
X371343Y-150314D01*
X371780Y-152647D01*
X371343Y-154980D01*
X370251Y-156730D01*
X368286Y-157606D01*
X363046D01*
G01X389716Y-148856D02*
X388406Y-147980D01*
X386878Y-147397D01*
X385131D01*
X383166Y-148272D01*
X381638Y-149730D01*
X380546Y-151481D01*
X379673Y-154397D01*
X379454Y-157022D01*
X379891Y-159647D01*
X380546Y-161397D01*
X381856Y-163147D01*
X383385Y-164314D01*
X384913Y-164897D01*
X386441D01*
X387970Y-164314D01*
X389280Y-163439D01*
X390372Y-162273D01*
G01X404159Y-155564D02*
X405033Y-154689D01*
X405688Y-153231D01*
X406125Y-151188D01*
X405688Y-149439D01*
X404815Y-148272D01*
X403286Y-147397D01*
X397391D01*
Y-164897D01*
X404596D01*
X406125Y-163731D01*
X406998Y-161980D01*
X407435Y-159939D01*
X406998Y-157897D01*
X405688Y-156147D01*
X404159Y-155564D01*
X397391D01*
G01X413363Y-170730D02*
X426463D01*
G01X432391Y-164897D02*
Y-147397D01*
X442435Y-164897D01*
Y-147397D01*
G01X454913Y-164897D02*
X453166Y-164605D01*
X451638Y-163439D01*
X450328Y-161689D01*
X449454Y-159647D01*
X449018Y-157314D01*
Y-154980D01*
X449454Y-152647D01*
X450328Y-150605D01*
X451638Y-148856D01*
X453166Y-147689D01*
X454913Y-147397D01*
X456659Y-147689D01*
X458188Y-148856D01*
X459498Y-150605D01*
X460372Y-152647D01*
X460808Y-154980D01*
Y-157314D01*
X460372Y-159647D01*
X459498Y-161689D01*
X458188Y-163439D01*
X456659Y-164605D01*
X454913Y-164897D01*
G01X505754Y-147397D02*
X511213Y-164897D01*
X516672Y-147397D01*
G01X533080Y-164897D02*
X524346D01*
Y-147397D01*
X533080D01*
G01X529586Y-155855D02*
X524346D01*
G01X541846Y-164897D02*
Y-147397D01*
X547305D01*
X549051Y-148272D01*
X550143Y-149439D01*
X550580Y-151772D01*
X550143Y-154106D01*
X548833Y-155564D01*
X547305Y-156439D01*
X541846D01*
G01X547305D02*
X550580Y-164897D01*
G01X563713Y-165480D02*
X563276Y-165189D01*
Y-164605D01*
X563713Y-164314D01*
X564150Y-164605D01*
Y-165189D01*
X563713Y-165480D01*
G01X524128Y-207564D02*
X525875Y-209022D01*
X527840Y-209897D01*
X529586D01*
X531333Y-209022D01*
X532643Y-207564D01*
X533298Y-205522D01*
X532861Y-203481D01*
X531770Y-201730D01*
X529805Y-200564D01*
X527185Y-199980D01*
X525656Y-198814D01*
X525001Y-196772D01*
X525438Y-194730D01*
X526530Y-193272D01*
X528058Y-192397D01*
X529586D01*
X531115Y-192980D01*
X532425Y-194439D01*
G01X540754Y-209897D02*
X546213Y-192397D01*
X551672Y-209897D01*
G01X549706Y-203772D02*
X542719D01*
G01X643663Y-192397D02*
Y-209897D01*
G01X638641Y-192397D02*
X648685D01*
G01X655486Y-209897D02*
Y-192397D01*
X661163Y-206980D01*
X666840Y-192397D01*
Y-209897D01*
G01X673204D02*
X678663Y-192397D01*
X684122Y-209897D01*
G01X682156Y-203772D02*
X675169D01*
G01X691578Y-207564D02*
X693325Y-209022D01*
X695290Y-209897D01*
X697036D01*
X698783Y-209022D01*
X700093Y-207564D01*
X700748Y-205522D01*
X700311Y-203481D01*
X699220Y-201730D01*
X697255Y-200564D01*
X694635Y-199980D01*
X693106Y-198814D01*
X692451Y-196772D01*
X692888Y-194730D01*
X693980Y-193272D01*
X695508Y-192397D01*
X697036D01*
X698565Y-192980D01*
X699875Y-194439D01*
G01X708860Y-209897D02*
Y-192397D01*
G01X717156D02*
X708860Y-203189D01*
G01X718466Y-209897D02*
X712571Y-198231D01*
G01X630546Y-147397D02*
Y-164897D01*
X639280D01*
G01X656343D02*
Y-153231D01*
G01Y-155272D02*
X655470Y-154106D01*
X654159Y-153522D01*
X652631Y-153231D01*
X651103Y-153814D01*
X649793Y-154980D01*
X648919Y-156730D01*
X648483Y-159064D01*
X648919Y-161397D01*
X649793Y-163147D01*
X651103Y-164314D01*
X652631Y-164897D01*
X654159Y-164605D01*
X655470Y-163731D01*
X656343Y-162564D01*
G01X665328Y-170147D02*
X666638Y-170730D01*
X668385Y-170147D01*
X669476Y-168981D01*
X670350Y-167522D01*
X671659Y-162856D01*
X674498Y-153231D01*
G01X667511D02*
X671659Y-162856D01*
G01X684138Y-157022D02*
X691125D01*
X690470Y-154980D01*
X689378Y-153814D01*
X687850Y-153231D01*
X686321Y-153522D01*
X685011Y-154397D01*
X684138Y-156439D01*
X683701Y-158189D01*
Y-159939D01*
X684138Y-161689D01*
X685230Y-163439D01*
X686540Y-164605D01*
X688068Y-164897D01*
X689596Y-164314D01*
X691125Y-162564D01*
G01X701856Y-164897D02*
Y-153231D01*
G01Y-155564D02*
X702948Y-154397D01*
X704040Y-153522D01*
X705568Y-153231D01*
X706659Y-153522D01*
X707970Y-154397D01*
G01X719138Y-162856D02*
X720230Y-164022D01*
X721758Y-164897D01*
X723068D01*
X724378Y-164314D01*
X725251Y-163439D01*
X725688Y-162273D01*
X725470Y-160522D01*
X724596Y-159647D01*
X720666Y-157897D01*
X719793Y-155855D01*
X720230Y-154397D01*
X721103Y-153522D01*
X722413Y-153231D01*
X723723Y-153522D01*
X725033Y-154397D01*
G01X790596Y-209897D02*
Y-192397D01*
X796055D01*
X797801Y-193272D01*
X798893Y-194439D01*
X799330Y-196772D01*
X798893Y-199106D01*
X797583Y-200564D01*
X796055Y-201439D01*
X790596D01*
G01X796055D02*
X799330Y-209897D01*
G01X809188Y-202022D02*
X816175D01*
X815520Y-199980D01*
X814428Y-198814D01*
X812900Y-198231D01*
X811371Y-198522D01*
X810061Y-199397D01*
X809188Y-201439D01*
X808751Y-203189D01*
Y-204939D01*
X809188Y-206689D01*
X810280Y-208439D01*
X811590Y-209605D01*
X813118Y-209897D01*
X814646Y-209314D01*
X816175Y-207564D01*
G01X826033Y-209897D02*
Y-192397D01*
G01Y-201147D02*
X827125Y-199397D01*
X828435Y-198522D01*
X829745Y-198231D01*
X831709Y-198814D01*
X833020Y-199980D01*
X833893Y-202022D01*
Y-204355D01*
X833456Y-206689D01*
X832583Y-208439D01*
X831055Y-209605D01*
X829745Y-209897D01*
X828435Y-209605D01*
X827125Y-208731D01*
X826033Y-207273D01*
G01X844188Y-202022D02*
X851175D01*
X850520Y-199980D01*
X849428Y-198814D01*
X847900Y-198231D01*
X846371Y-198522D01*
X845061Y-199397D01*
X844188Y-201439D01*
X843751Y-203189D01*
Y-204939D01*
X844188Y-206689D01*
X845280Y-208439D01*
X846590Y-209605D01*
X848118Y-209897D01*
X849646Y-209314D01*
X851175Y-207564D01*
G01X868456Y-199689D02*
X866928Y-198522D01*
X865618Y-198231D01*
X863871Y-198814D01*
X862561Y-199980D01*
X861688Y-202022D01*
X861469Y-204064D01*
X861688Y-206106D01*
X862561Y-207856D01*
X863871Y-209314D01*
X865618Y-209897D01*
X867146Y-209314D01*
X868456Y-208147D01*
G01X885956Y-199689D02*
X884428Y-198522D01*
X883118Y-198231D01*
X881371Y-198814D01*
X880061Y-199980D01*
X879188Y-202022D01*
X878969Y-204064D01*
X879188Y-206106D01*
X880061Y-207856D01*
X881371Y-209314D01*
X883118Y-209897D01*
X884646Y-209314D01*
X885956Y-208147D01*
G01X903893Y-209897D02*
Y-198231D01*
G01Y-200272D02*
X903020Y-199106D01*
X901709Y-198522D01*
X900181Y-198231D01*
X898653Y-198814D01*
X897343Y-199980D01*
X896469Y-201730D01*
X896033Y-204064D01*
X896469Y-206397D01*
X897343Y-208147D01*
X898653Y-209314D01*
X900181Y-209897D01*
X901709Y-209605D01*
X903020Y-208731D01*
X903893Y-207564D01*
G01X781410Y-164897D02*
Y-147397D01*
X785776D01*
X787523Y-148272D01*
X788833Y-149439D01*
X789925Y-151188D01*
X790798Y-153231D01*
X791016Y-156147D01*
X790798Y-159064D01*
X789925Y-161106D01*
X788833Y-162856D01*
X787523Y-164022D01*
X785776Y-164897D01*
X781410D01*
G01X800438Y-157022D02*
X807425D01*
X806770Y-154980D01*
X805678Y-153814D01*
X804150Y-153231D01*
X802621Y-153522D01*
X801311Y-154397D01*
X800438Y-156439D01*
X800001Y-158189D01*
Y-159939D01*
X800438Y-161689D01*
X801530Y-163439D01*
X802840Y-164605D01*
X804368Y-164897D01*
X805896Y-164314D01*
X807425Y-162564D01*
G01X817938Y-162856D02*
X819030Y-164022D01*
X820558Y-164897D01*
X821868D01*
X823178Y-164314D01*
X824051Y-163439D01*
X824488Y-162273D01*
X824270Y-160522D01*
X823396Y-159647D01*
X819466Y-157897D01*
X818593Y-155855D01*
X819030Y-154397D01*
X819903Y-153522D01*
X821213Y-153231D01*
X822523Y-153522D01*
X823833Y-154397D01*
G01X838713Y-153231D02*
Y-164897D01*
G01Y-148564D02*
X838276Y-148272D01*
Y-147689D01*
X838713Y-147397D01*
X839150Y-147689D01*
Y-148272D01*
X838713Y-148564D01*
G01X853156Y-169272D02*
X854685Y-170439D01*
X856431Y-170730D01*
X857959Y-170439D01*
X859270Y-168981D01*
X860143Y-166939D01*
Y-153231D01*
G01Y-155564D02*
X859270Y-154397D01*
X857959Y-153522D01*
X856431Y-153231D01*
X854685Y-153814D01*
X853593Y-154980D01*
X852719Y-157022D01*
X852283Y-159064D01*
X852501Y-160814D01*
X853375Y-162856D01*
X854685Y-164314D01*
X856431Y-164897D01*
X857741Y-164605D01*
X859270Y-163439D01*
X860143Y-162273D01*
G01X870001Y-164897D02*
Y-153231D01*
G01Y-156147D02*
X870875Y-154689D01*
X872185Y-153522D01*
X873931Y-153231D01*
X875459Y-153522D01*
X876770Y-154689D01*
X877425Y-156730D01*
Y-164897D01*
G01X887938Y-157022D02*
X894925D01*
X894270Y-154980D01*
X893178Y-153814D01*
X891650Y-153231D01*
X890121Y-153522D01*
X888811Y-154397D01*
X887938Y-156439D01*
X887501Y-158189D01*
Y-159939D01*
X887938Y-161689D01*
X889030Y-163439D01*
X890340Y-164605D01*
X891868Y-164897D01*
X893396Y-164314D01*
X894925Y-162564D01*
G01X905656Y-164897D02*
Y-153231D01*
G01Y-155564D02*
X906748Y-154397D01*
X907840Y-153522D01*
X909368Y-153231D01*
X910459Y-153522D01*
X911770Y-154397D01*
G01X952413Y-192397D02*
X950666Y-192980D01*
X949356Y-194439D01*
X948483Y-196188D01*
X947828Y-198522D01*
X947610Y-201147D01*
X947828Y-203772D01*
X948483Y-206106D01*
X949356Y-207856D01*
X950666Y-209314D01*
X952413Y-209897D01*
X954159Y-209314D01*
X955470Y-207856D01*
X956343Y-206106D01*
X956998Y-203772D01*
X957216Y-201147D01*
X956998Y-198522D01*
X956343Y-196188D01*
X955470Y-194439D01*
X954159Y-192980D01*
X952413Y-192397D01*
G01X969913Y-209897D02*
X971441Y-209605D01*
X973188Y-208731D01*
X974280Y-207273D01*
X974716Y-205230D01*
X974280Y-203189D01*
X972970Y-201439D01*
X971005Y-200564D01*
X968821D01*
X967511Y-199980D01*
X966419Y-198522D01*
X965983Y-196481D01*
X966638Y-194439D01*
X968166Y-192980D01*
X969913Y-192397D01*
X971659Y-192980D01*
X973188Y-194439D01*
X973843Y-196481D01*
X973406Y-198522D01*
X972315Y-199980D01*
X971005Y-200564D01*
X968821D01*
X966856Y-201439D01*
X965546Y-203189D01*
X965110Y-205230D01*
X965546Y-207273D01*
X966638Y-208731D01*
X968385Y-209605D01*
X969913Y-209897D01*
G01X983483Y-210480D02*
X991343Y-192397D01*
G01X1004913D02*
X1003166Y-192980D01*
X1001856Y-194439D01*
X1000983Y-196188D01*
X1000328Y-198522D01*
X1000110Y-201147D01*
X1000328Y-203772D01*
X1000983Y-206106D01*
X1001856Y-207856D01*
X1003166Y-209314D01*
X1004913Y-209897D01*
X1006659Y-209314D01*
X1007970Y-207856D01*
X1008843Y-206106D01*
X1009498Y-203772D01*
X1009716Y-201147D01*
X1009498Y-198522D01*
X1008843Y-196188D01*
X1007970Y-194439D01*
X1006659Y-192980D01*
X1004913Y-192397D01*
G01X1022413Y-209897D02*
Y-192397D01*
X1019793Y-195897D01*
G01Y-209897D02*
X1025033D01*
G01X1035983Y-210480D02*
X1043843Y-192397D01*
G01X1053265Y-195314D02*
X1054575Y-193564D01*
X1056103Y-192689D01*
X1057850Y-192397D01*
X1060033Y-192980D01*
X1061561Y-194439D01*
X1061998Y-196188D01*
X1061780Y-197939D01*
X1060906Y-199397D01*
X1056540Y-202314D01*
X1054575Y-204355D01*
X1053265Y-207273D01*
X1052828Y-209897D01*
X1061998D01*
G01X1074913Y-192397D02*
X1073166Y-192980D01*
X1071856Y-194439D01*
X1070983Y-196188D01*
X1070328Y-198522D01*
X1070110Y-201147D01*
X1070328Y-203772D01*
X1070983Y-206106D01*
X1071856Y-207856D01*
X1073166Y-209314D01*
X1074913Y-209897D01*
X1076659Y-209314D01*
X1077970Y-207856D01*
X1078843Y-206106D01*
X1079498Y-203772D01*
X1079716Y-201147D01*
X1079498Y-198522D01*
X1078843Y-196188D01*
X1077970Y-194439D01*
X1076659Y-192980D01*
X1074913Y-192397D01*
G01X1092413Y-209897D02*
Y-192397D01*
X1089793Y-195897D01*
G01Y-209897D02*
X1095033D01*
G01X1112533D02*
Y-192397D01*
X1104454Y-204939D01*
X1115372D01*
G01X1000110Y-164897D02*
Y-147397D01*
X1004476D01*
X1006223Y-148272D01*
X1007533Y-149439D01*
X1008625Y-151188D01*
X1009498Y-153231D01*
X1009716Y-156147D01*
X1009498Y-159064D01*
X1008625Y-161106D01*
X1007533Y-162856D01*
X1006223Y-164022D01*
X1004476Y-164897D01*
X1000110D01*
G01X1026343D02*
Y-153231D01*
G01Y-155272D02*
X1025470Y-154106D01*
X1024159Y-153522D01*
X1022631Y-153231D01*
X1021103Y-153814D01*
X1019793Y-154980D01*
X1018919Y-156730D01*
X1018483Y-159064D01*
X1018919Y-161397D01*
X1019793Y-163147D01*
X1021103Y-164314D01*
X1022631Y-164897D01*
X1024159Y-164605D01*
X1025470Y-163731D01*
X1026343Y-162564D01*
G01X1039913Y-147397D02*
Y-164897D01*
G01X1036856Y-153231D02*
X1042970D01*
G01X1054138Y-157022D02*
X1061125D01*
X1060470Y-154980D01*
X1059378Y-153814D01*
X1057850Y-153231D01*
X1056321Y-153522D01*
X1055011Y-154397D01*
X1054138Y-156439D01*
X1053701Y-158189D01*
Y-159939D01*
X1054138Y-161689D01*
X1055230Y-163439D01*
X1056540Y-164605D01*
X1058068Y-164897D01*
X1059596Y-164314D01*
X1061125Y-162564D01*
G54D59*
X154521Y132477D03*
Y107677D03*
X133521Y132477D03*
Y107677D03*
X861999Y139450D03*
Y114650D03*
X882499Y139450D03*
Y114650D03*
G54D77*
X336000Y1962500D03*
Y1971500D03*
G54D68*
X145000Y539050D03*
X141125Y531550D03*
X148875D03*
X129600Y1334250D03*
X125725Y1326750D03*
X133475D03*
X161700Y1689550D03*
X157825Y1682050D03*
X165575D03*
X183900Y925750D03*
X180025Y918250D03*
X187775D03*
X307000Y105150D03*
X303125Y97650D03*
X310875D03*
G54D69*
X156499Y1297113D03*
X161499D03*
X166499D03*
X171499D03*
Y1277113D03*
X166499D03*
X161499D03*
X156499D03*
X157499Y1720113D03*
X162499D03*
X167499D03*
X172499D03*
Y1700113D03*
X167499D03*
X162499D03*
X157499D03*
X191499Y534113D03*
X196499D03*
X201499D03*
X206499D03*
Y514113D03*
X201499D03*
X196499D03*
X191499D03*
X214999Y932613D03*
X219999D03*
X224999D03*
X229999D03*
Y912613D03*
X224999D03*
X219999D03*
X214999D03*
X247299Y1136650D03*
X242299D03*
X237299D03*
X232299D03*
Y1156650D03*
X237299D03*
X242299D03*
X247299D03*
X345999Y106550D03*
X350999D03*
X355999D03*
X360999D03*
Y86550D03*
X355999D03*
X350999D03*
X345999D03*
G54D78*
X666399Y1806699D03*
Y1808664D03*
Y1810634D03*
Y1812604D03*
Y1814569D03*
X682699D03*
Y1812604D03*
Y1810634D03*
Y1808664D03*
Y1806699D03*
G54D79*
X753949Y1801294D03*
Y1803854D03*
Y1806414D03*
Y1808974D03*
X776149Y1803854D03*
Y1801294D03*
Y1808974D03*
Y1806414D03*
M02*
